(kicad_sch
	(version 20250114)
	(generator "eeschema")
	(generator_version "9.0")
	(paper "A3")
	(title_block
		(title "LPDDR5 Testbed")
		(date "2023-12-19")
		(rev "1.0.0")
	)
	(text "@2A"
		(exclude_from_sim no)
		(at 290.195 121.92 0)
		(effects
			(font
				(size 1.27 1.27)
			)
			(justify left bottom)
		)
	)
	(text "Soft start delay time slot"
		(exclude_from_sim no)
		(at 224.155 53.975 0)
		(effects
			(font
				(size 1.27 1.27)
			)
			(justify left bottom)
		)
	)
	(text "X"
		(exclude_from_sim no)
		(at 236.22 64.135 0)
		(effects
			(font
				(size 1.27 1.27)
			)
			(justify left bottom)
		)
	)
	(text "@2A"
		(exclude_from_sim no)
		(at 290.195 106.68 0)
		(effects
			(font
				(size 1.27 1.27)
			)
			(justify left bottom)
		)
	)
	(text "VOUT4"
		(exclude_from_sim no)
		(at 221.615 66.675 0)
		(effects
			(font
				(size 1.27 1.27)
			)
			(justify left bottom)
		)
	)
	(text "VOUT1"
		(exclude_from_sim no)
		(at 221.615 59.055 0)
		(effects
			(font
				(size 1.27 1.27)
			)
			(justify left bottom)
		)
	)
	(text "@3A"
		(exclude_from_sim no)
		(at 290.195 91.44 0)
		(effects
			(font
				(size 1.27 1.27)
			)
			(justify left bottom)
		)
	)
	(text "Note: \nDefault I2C addres: 0x68"
		(exclude_from_sim no)
		(at 189.865 127 0)
		(effects
			(font
				(size 1.27 1.27)
			)
			(justify left bottom)
		)
	)
	(text "Note:\nPower from QWIIC should be\nsupplied only for the time of\nintial programming of MPM54304\n"
		(exclude_from_sim no)
		(at 123.19 83.82 0)
		(effects
			(font
				(size 1.27 1.27)
			)
			(justify left bottom)
		)
	)
	(text "Calculated\nfor range\n0.4-1.4V"
		(exclude_from_sim no)
		(at 283.845 202.565 0)
		(effects
			(font
				(size 1.27 1.27)
			)
			(justify left bottom)
		)
	)
	(text "1->3->2->4"
		(exclude_from_sim no)
		(at 231.775 69.215 0)
		(effects
			(font
				(size 1.27 1.27)
			)
			(justify left bottom)
		)
	)
	(text "X"
		(exclude_from_sim no)
		(at 241.3 61.595 0)
		(effects
			(font
				(size 1.27 1.27)
			)
			(justify left bottom)
		)
	)
	(text "VOUT3"
		(exclude_from_sim no)
		(at 221.615 64.135 0)
		(effects
			(font
				(size 1.27 1.27)
			)
			(justify left bottom)
		)
	)
	(text "@3A"
		(exclude_from_sim no)
		(at 340.36 180.975 0)
		(effects
			(font
				(size 1.27 1.27)
			)
			(justify left bottom)
		)
	)
	(text "X"
		(exclude_from_sim no)
		(at 246.38 66.675 0)
		(effects
			(font
				(size 1.27 1.27)
			)
			(justify left bottom)
		)
	)
	(text "VOUT2"
		(exclude_from_sim no)
		(at 221.615 61.595 0)
		(effects
			(font
				(size 1.27 1.27)
			)
			(justify left bottom)
		)
	)
	(text "@3A"
		(exclude_from_sim no)
		(at 290.195 76.835 0)
		(effects
			(font
				(size 1.27 1.27)
			)
			(justify left bottom)
		)
	)
	(text "0ms 1ms 2ms 3ms"
		(exclude_from_sim no)
		(at 229.87 56.515 0)
		(effects
			(font
				(size 1.27 1.27)
			)
			(justify left bottom)
		)
	)
	(text "X"
		(exclude_from_sim no)
		(at 231.14 59.055 0)
		(effects
			(font
				(size 1.27 1.27)
			)
			(justify left bottom)
		)
	)
	(text "IMON resistor calculated\nso that 1A <-> 1V"
		(exclude_from_sim no)
		(at 177.8 208.915 0)
		(effects
			(font
				(size 1.27 1.27)
			)
			(justify left bottom)
		)
	)
	(junction
		(at 193.04 97.79)
		(diameter 0)
		(color 0 0 0 0)
	)
	(junction
		(at 231.14 114.3)
		(diameter 0)
		(color 0 0 0 0)
	)
	(junction
		(at 231.14 96.52)
		(diameter 0)
		(color 0 0 0 0)
	)
	(junction
		(at 266.7 119.38)
		(diameter 0)
		(color 0 0 0 0)
	)
	(junction
		(at 276.225 193.675)
		(diameter 0)
		(color 0 0 0 0)
	)
	(junction
		(at 257.81 88.9)
		(diameter 0)
		(color 0 0 0 0)
	)
	(junction
		(at 162.56 178.435)
		(diameter 0)
		(color 0 0 0 0)
	)
	(junction
		(at 193.04 100.33)
		(diameter 0)
		(color 0 0 0 0)
	)
	(junction
		(at 281.305 178.435)
		(diameter 0)
		(color 0 0 0 0)
	)
	(junction
		(at 180.975 57.785)
		(diameter 0)
		(color 0 0 0 0)
	)
	(junction
		(at 274.955 74.295)
		(diameter 0)
		(color 0 0 0 0)
	)
	(junction
		(at 319.405 178.435)
		(diameter 0)
		(color 0 0 0 0)
	)
	(junction
		(at 168.91 178.435)
		(diameter 0)
		(color 0 0 0 0)
	)
	(junction
		(at 281.305 186.055)
		(diameter 0)
		(color 0 0 0 0)
	)
	(junction
		(at 295.91 178.435)
		(diameter 0)
		(color 0 0 0 0)
	)
	(junction
		(at 254 104.14)
		(diameter 0)
		(color 0 0 0 0)
	)
	(junction
		(at 176.53 178.435)
		(diameter 0)
		(color 0 0 0 0)
	)
	(junction
		(at 247.015 106.68)
		(diameter 0)
		(color 0 0 0 0)
	)
	(junction
		(at 302.26 178.435)
		(diameter 0)
		(color 0 0 0 0)
	)
	(junction
		(at 254 91.44)
		(diameter 0)
		(color 0 0 0 0)
	)
	(junction
		(at 196.85 196.215)
		(diameter 0)
		(color 0 0 0 0)
	)
	(junction
		(at 142.875 105.41)
		(diameter 0)
		(color 0 0 0 0)
	)
	(junction
		(at 142.875 102.87)
		(diameter 0)
		(color 0 0 0 0)
	)
	(junction
		(at 176.53 97.79)
		(diameter 0)
		(color 0 0 0 0)
	)
	(junction
		(at 266.7 104.14)
		(diameter 0)
		(color 0 0 0 0)
	)
	(junction
		(at 257.81 74.295)
		(diameter 0)
		(color 0 0 0 0)
	)
	(junction
		(at 266.7 74.295)
		(diameter 0)
		(color 0 0 0 0)
	)
	(junction
		(at 231.14 83.82)
		(diameter 0)
		(color 0 0 0 0)
	)
	(junction
		(at 176.53 186.055)
		(diameter 0)
		(color 0 0 0 0)
	)
	(junction
		(at 291.465 74.295)
		(diameter 0)
		(color 0 0 0 0)
	)
	(junction
		(at 274.955 119.38)
		(diameter 0)
		(color 0 0 0 0)
	)
	(junction
		(at 291.465 104.14)
		(diameter 0)
		(color 0 0 0 0)
	)
	(junction
		(at 184.15 183.515)
		(diameter 0)
		(color 0 0 0 0)
	)
	(junction
		(at 342.265 178.435)
		(diameter 0)
		(color 0 0 0 0)
	)
	(junction
		(at 291.465 88.9)
		(diameter 0)
		(color 0 0 0 0)
	)
	(junction
		(at 274.955 88.9)
		(diameter 0)
		(color 0 0 0 0)
	)
	(junction
		(at 174.625 100.33)
		(diameter 0)
		(color 0 0 0 0)
	)
	(junction
		(at 274.955 104.14)
		(diameter 0)
		(color 0 0 0 0)
	)
	(junction
		(at 189.23 186.055)
		(diameter 0)
		(color 0 0 0 0)
	)
	(junction
		(at 231.14 104.14)
		(diameter 0)
		(color 0 0 0 0)
	)
	(junction
		(at 227.33 214.63)
		(diameter 0)
		(color 0 0 0 0)
	)
	(junction
		(at 254 78.74)
		(diameter 0)
		(color 0 0 0 0)
	)
	(junction
		(at 254 114.3)
		(diameter 0)
		(color 0 0 0 0)
	)
	(junction
		(at 231.14 214.63)
		(diameter 0)
		(color 0 0 0 0)
	)
	(junction
		(at 159.385 57.785)
		(diameter 0)
		(color 0 0 0 0)
	)
	(junction
		(at 223.52 106.68)
		(diameter 0)
		(color 0 0 0 0)
	)
	(junction
		(at 266.7 88.9)
		(diameter 0)
		(color 0 0 0 0)
	)
	(junction
		(at 291.465 119.38)
		(diameter 0)
		(color 0 0 0 0)
	)
	(junction
		(at 247.015 99.06)
		(diameter 0)
		(color 0 0 0 0)
	)
	(junction
		(at 170.815 57.785)
		(diameter 0)
		(color 0 0 0 0)
	)
	(junction
		(at 247.015 116.84)
		(diameter 0)
		(color 0 0 0 0)
	)
	(no_connect
		(at 222.25 93.98)
	)
	(no_connect
		(at 281.305 197.485)
	)
	(no_connect
		(at 222.25 81.28)
	)
	(bus_entry
		(at 174.625 102.87)
		(size -1.27 1.27)
		(stroke
			(width 0)
			(type default)
		)
	)
	(bus_entry
		(at 176.53 102.87)
		(size -1.27 1.27)
		(stroke
			(width 0)
			(type default)
		)
	)
	(wire
		(pts
			(xy 254 91.44) (xy 254 88.9)
		)
		(stroke
			(width 0)
			(type default)
		)
	)
	(polyline
		(pts
			(xy 220.345 51.435) (xy 220.345 61.595)
		)
		(stroke
			(width 0)
			(type dash)
		)
	)
	(wire
		(pts
			(xy 180.975 73.66) (xy 180.975 74.93)
		)
		(stroke
			(width 0)
			(type default)
		)
	)
	(wire
		(pts
			(xy 254 104.14) (xy 266.7 104.14)
		)
		(stroke
			(width 0)
			(type default)
		)
	)
	(wire
		(pts
			(xy 218.44 196.215) (xy 219.71 196.215)
		)
		(stroke
			(width 0)
			(type default)
		)
	)
	(wire
		(pts
			(xy 231.14 116.84) (xy 231.14 114.3)
		)
		(stroke
			(width 0)
			(type default)
		)
	)
	(wire
		(pts
			(xy 277.495 193.675) (xy 276.225 193.675)
		)
		(stroke
			(width 0)
			(type default)
		)
	)
	(wire
		(pts
			(xy 222.25 101.6) (xy 254 101.6)
		)
		(stroke
			(width 0)
			(type default)
		)
	)
	(wire
		(pts
			(xy 219.71 202.565) (xy 219.71 203.835)
		)
		(stroke
			(width 0)
			(type default)
		)
	)
	(polyline
		(pts
			(xy 215.265 127.635) (xy 189.23 127.635)
		)
		(stroke
			(width 0)
			(type dash)
		)
	)
	(wire
		(pts
			(xy 191.135 93.345) (xy 193.04 93.345)
		)
		(stroke
			(width 0)
			(type default)
		)
	)
	(wire
		(pts
			(xy 247.015 106.68) (xy 247.015 99.06)
		)
		(stroke
			(width 0)
			(type default)
		)
	)
	(wire
		(pts
			(xy 241.3 106.68) (xy 247.015 106.68)
		)
		(stroke
			(width 0)
			(type default)
		)
	)
	(wire
		(pts
			(xy 257.81 88.9) (xy 257.81 90.17)
		)
		(stroke
			(width 0)
			(type default)
		)
	)
	(wire
		(pts
			(xy 247.015 99.06) (xy 247.015 86.36)
		)
		(stroke
			(width 0)
			(type default)
		)
	)
	(polyline
		(pts
			(xy 229.235 55.245) (xy 229.235 66.675)
		)
		(stroke
			(width 0)
			(type dash)
		)
	)
	(wire
		(pts
			(xy 198.12 183.515) (xy 184.15 183.515)
		)
		(stroke
			(width 0)
			(type default)
		)
	)
	(polyline
		(pts
			(xy 249.555 59.055) (xy 249.555 61.595)
		)
		(stroke
			(width 0)
			(type dash)
		)
	)
	(wire
		(pts
			(xy 236.22 86.36) (xy 231.14 86.36)
		)
		(stroke
			(width 0)
			(type default)
		)
	)
	(polyline
		(pts
			(xy 249.555 59.055) (xy 249.555 51.435)
		)
		(stroke
			(width 0)
			(type dash)
		)
	)
	(wire
		(pts
			(xy 162.56 178.435) (xy 168.91 178.435)
		)
		(stroke
			(width 0)
			(type default)
		)
	)
	(polyline
		(pts
			(xy 244.475 53.975) (xy 244.475 66.675)
		)
		(stroke
			(width 0)
			(type dash)
		)
	)
	(wire
		(pts
			(xy 241.3 116.84) (xy 247.015 116.84)
		)
		(stroke
			(width 0)
			(type default)
		)
	)
	(wire
		(pts
			(xy 168.91 178.435) (xy 168.91 179.705)
		)
		(stroke
			(width 0)
			(type default)
		)
	)
	(wire
		(pts
			(xy 276.225 187.325) (xy 276.225 186.055)
		)
		(stroke
			(width 0)
			(type default)
		)
	)
	(wire
		(pts
			(xy 231.14 104.14) (xy 236.22 104.14)
		)
		(stroke
			(width 0)
			(type default)
		)
	)
	(wire
		(pts
			(xy 223.52 106.68) (xy 223.52 120.015)
		)
		(stroke
			(width 0)
			(type default)
		)
	)
	(wire
		(pts
			(xy 257.81 74.295) (xy 266.7 74.295)
		)
		(stroke
			(width 0)
			(type default)
		)
	)
	(polyline
		(pts
			(xy 122.555 74.93) (xy 156.21 74.93)
		)
		(stroke
			(width 0)
			(type dash)
		)
	)
	(wire
		(pts
			(xy 257.81 74.295) (xy 257.81 75.565)
		)
		(stroke
			(width 0)
			(type default)
		)
	)
	(wire
		(pts
			(xy 236.22 99.06) (xy 231.14 99.06)
		)
		(stroke
			(width 0)
			(type default)
		)
	)
	(wire
		(pts
			(xy 276.225 193.675) (xy 276.225 194.945)
		)
		(stroke
			(width 0)
			(type default)
		)
	)
	(wire
		(pts
			(xy 180.975 57.785) (xy 180.975 59.055)
		)
		(stroke
			(width 0)
			(type default)
		)
	)
	(wire
		(pts
			(xy 274.955 117.475) (xy 274.955 119.38)
		)
		(stroke
			(width 0)
			(type default)
		)
	)
	(wire
		(pts
			(xy 285.115 74.295) (xy 291.465 74.295)
		)
		(stroke
			(width 0)
			(type default)
		)
	)
	(wire
		(pts
			(xy 274.955 104.14) (xy 280.035 104.14)
		)
		(stroke
			(width 0)
			(type default)
		)
	)
	(wire
		(pts
			(xy 231.14 214.63) (xy 237.49 214.63)
		)
		(stroke
			(width 0)
			(type default)
		)
	)
	(wire
		(pts
			(xy 274.955 72.39) (xy 274.955 74.295)
		)
		(stroke
			(width 0)
			(type default)
		)
	)
	(wire
		(pts
			(xy 302.26 178.435) (xy 302.26 180.975)
		)
		(stroke
			(width 0)
			(type default)
		)
	)
	(wire
		(pts
			(xy 231.14 193.675) (xy 231.14 201.93)
		)
		(stroke
			(width 0)
			(type default)
		)
	)
	(wire
		(pts
			(xy 241.3 96.52) (xy 254 96.52)
		)
		(stroke
			(width 0)
			(type default)
		)
	)
	(wire
		(pts
			(xy 302.26 178.435) (xy 319.405 178.435)
		)
		(stroke
			(width 0)
			(type default)
		)
	)
	(wire
		(pts
			(xy 222.25 114.3) (xy 231.14 114.3)
		)
		(stroke
			(width 0)
			(type default)
		)
	)
	(wire
		(pts
			(xy 281.305 179.705) (xy 281.305 178.435)
		)
		(stroke
			(width 0)
			(type default)
		)
	)
	(wire
		(pts
			(xy 191.135 103.505) (xy 193.04 103.505)
		)
		(stroke
			(width 0)
			(type default)
		)
	)
	(polyline
		(pts
			(xy 220.345 61.595) (xy 220.345 66.675)
		)
		(stroke
			(width 0)
			(type dash)
		)
	)
	(wire
		(pts
			(xy 176.53 178.435) (xy 198.12 178.435)
		)
		(stroke
			(width 0)
			(type default)
		)
	)
	(wire
		(pts
			(xy 236.22 106.68) (xy 231.14 106.68)
		)
		(stroke
			(width 0)
			(type default)
		)
	)
	(wire
		(pts
			(xy 162.56 178.435) (xy 162.56 179.705)
		)
		(stroke
			(width 0)
			(type default)
		)
	)
	(wire
		(pts
			(xy 141.605 100.33) (xy 174.625 100.33)
		)
		(stroke
			(width 0)
			(type default)
		)
	)
	(wire
		(pts
			(xy 189.23 196.215) (xy 189.23 197.485)
		)
		(stroke
			(width 0)
			(type default)
		)
	)
	(polyline
		(pts
			(xy 189.23 122.555) (xy 215.265 122.555)
		)
		(stroke
			(width 0)
			(type dash)
		)
	)
	(wire
		(pts
			(xy 266.7 74.295) (xy 266.7 75.565)
		)
		(stroke
			(width 0)
			(type default)
		)
	)
	(wire
		(pts
			(xy 285.115 104.14) (xy 291.465 104.14)
		)
		(stroke
			(width 0)
			(type default)
		)
	)
	(wire
		(pts
			(xy 196.85 196.215) (xy 198.12 196.215)
		)
		(stroke
			(width 0)
			(type default)
		)
	)
	(wire
		(pts
			(xy 227.33 193.675) (xy 227.33 214.63)
		)
		(stroke
			(width 0)
			(type default)
		)
	)
	(polyline
		(pts
			(xy 249.555 53.975) (xy 229.235 53.975)
		)
		(stroke
			(width 0)
			(type dash)
		)
	)
	(wire
		(pts
			(xy 295.91 186.055) (xy 295.91 187.325)
		)
		(stroke
			(width 0)
			(type default)
		)
	)
	(bus
		(pts
			(xy 175.26 104.14) (xy 173.355 104.14)
		)
		(stroke
			(width 0)
			(type default)
		)
	)
	(wire
		(pts
			(xy 274.955 86.995) (xy 274.955 88.9)
		)
		(stroke
			(width 0)
			(type default)
		)
	)
	(wire
		(pts
			(xy 266.7 104.14) (xy 266.7 105.41)
		)
		(stroke
			(width 0)
			(type default)
		)
	)
	(wire
		(pts
			(xy 254 91.44) (xy 254 96.52)
		)
		(stroke
			(width 0)
			(type default)
		)
	)
	(wire
		(pts
			(xy 291.465 88.9) (xy 294.64 88.9)
		)
		(stroke
			(width 0)
			(type default)
		)
	)
	(wire
		(pts
			(xy 170.18 88.9) (xy 194.31 88.9)
		)
		(stroke
			(width 0)
			(type default)
		)
	)
	(wire
		(pts
			(xy 142.875 102.87) (xy 142.875 105.41)
		)
		(stroke
			(width 0)
			(type default)
		)
	)
	(wire
		(pts
			(xy 196.85 197.485) (xy 196.85 196.215)
		)
		(stroke
			(width 0)
			(type default)
		)
	)
	(polyline
		(pts
			(xy 220.345 56.515) (xy 249.555 56.515)
		)
		(stroke
			(width 0)
			(type dash)
		)
	)
	(wire
		(pts
			(xy 196.85 191.135) (xy 196.85 196.215)
		)
		(stroke
			(width 0)
			(type default)
		)
	)
	(polyline
		(pts
			(xy 220.345 59.055) (xy 249.555 59.055)
		)
		(stroke
			(width 0)
			(type dash)
		)
	)
	(wire
		(pts
			(xy 184.15 183.515) (xy 184.15 186.055)
		)
		(stroke
			(width 0)
			(type default)
		)
	)
	(wire
		(pts
			(xy 222.25 96.52) (xy 231.14 96.52)
		)
		(stroke
			(width 0)
			(type default)
		)
	)
	(wire
		(pts
			(xy 198.12 186.055) (xy 189.23 186.055)
		)
		(stroke
			(width 0)
			(type default)
		)
	)
	(wire
		(pts
			(xy 254 74.295) (xy 257.81 74.295)
		)
		(stroke
			(width 0)
			(type default)
		)
	)
	(wire
		(pts
			(xy 243.84 206.375) (xy 243.84 207.01)
		)
		(stroke
			(width 0)
			(type default)
		)
	)
	(wire
		(pts
			(xy 342.265 178.435) (xy 345.44 178.435)
		)
		(stroke
			(width 0)
			(type default)
		)
	)
	(wire
		(pts
			(xy 241.3 83.82) (xy 254 83.82)
		)
		(stroke
			(width 0)
			(type default)
		)
	)
	(wire
		(pts
			(xy 241.3 99.06) (xy 247.015 99.06)
		)
		(stroke
			(width 0)
			(type default)
		)
	)
	(wire
		(pts
			(xy 193.04 97.79) (xy 194.31 97.79)
		)
		(stroke
			(width 0)
			(type default)
		)
	)
	(wire
		(pts
			(xy 189.23 186.055) (xy 189.23 191.135)
		)
		(stroke
			(width 0)
			(type default)
		)
	)
	(wire
		(pts
			(xy 266.7 74.295) (xy 274.955 74.295)
		)
		(stroke
			(width 0)
			(type default)
		)
	)
	(wire
		(pts
			(xy 266.7 119.38) (xy 274.955 119.38)
		)
		(stroke
			(width 0)
			(type default)
		)
	)
	(wire
		(pts
			(xy 193.04 114.3) (xy 194.31 114.3)
		)
		(stroke
			(width 0)
			(type default)
		)
	)
	(polyline
		(pts
			(xy 229.235 53.975) (xy 229.235 55.245)
		)
		(stroke
			(width 0)
			(type dash)
		)
	)
	(wire
		(pts
			(xy 231.14 83.82) (xy 236.22 83.82)
		)
		(stroke
			(width 0)
			(type default)
		)
	)
	(wire
		(pts
			(xy 285.115 88.9) (xy 291.465 88.9)
		)
		(stroke
			(width 0)
			(type default)
		)
	)
	(wire
		(pts
			(xy 218.44 193.675) (xy 227.33 193.675)
		)
		(stroke
			(width 0)
			(type default)
		)
	)
	(wire
		(pts
			(xy 159.385 56.515) (xy 159.385 57.785)
		)
		(stroke
			(width 0)
			(type default)
		)
	)
	(wire
		(pts
			(xy 274.955 119.38) (xy 280.035 119.38)
		)
		(stroke
			(width 0)
			(type default)
		)
	)
	(wire
		(pts
			(xy 198.12 191.135) (xy 196.85 191.135)
		)
		(stroke
			(width 0)
			(type default)
		)
	)
	(wire
		(pts
			(xy 142.875 92.71) (xy 141.605 92.71)
		)
		(stroke
			(width 0)
			(type default)
		)
	)
	(wire
		(pts
			(xy 176.53 97.79) (xy 193.04 97.79)
		)
		(stroke
			(width 0)
			(type default)
		)
	)
	(wire
		(pts
			(xy 193.04 103.505) (xy 193.04 100.33)
		)
		(stroke
			(width 0)
			(type default)
		)
	)
	(wire
		(pts
			(xy 174.625 100.33) (xy 193.04 100.33)
		)
		(stroke
			(width 0)
			(type default)
		)
	)
	(wire
		(pts
			(xy 274.955 102.235) (xy 274.955 104.14)
		)
		(stroke
			(width 0)
			(type default)
		)
	)
	(polyline
		(pts
			(xy 189.23 122.555) (xy 189.23 127.635)
		)
		(stroke
			(width 0)
			(type dash)
		)
	)
	(wire
		(pts
			(xy 222.25 91.44) (xy 254 91.44)
		)
		(stroke
			(width 0)
			(type default)
		)
	)
	(polyline
		(pts
			(xy 215.265 122.555) (xy 215.265 127.635)
		)
		(stroke
			(width 0)
			(type dash)
		)
	)
	(wire
		(pts
			(xy 285.115 119.38) (xy 291.465 119.38)
		)
		(stroke
			(width 0)
			(type default)
		)
	)
	(wire
		(pts
			(xy 231.14 86.36) (xy 231.14 83.82)
		)
		(stroke
			(width 0)
			(type default)
		)
	)
	(wire
		(pts
			(xy 257.81 114.3) (xy 257.81 119.38)
		)
		(stroke
			(width 0)
			(type default)
		)
	)
	(wire
		(pts
			(xy 227.33 214.63) (xy 231.14 214.63)
		)
		(stroke
			(width 0)
			(type default)
		)
	)
	(wire
		(pts
			(xy 184.15 186.055) (xy 176.53 186.055)
		)
		(stroke
			(width 0)
			(type default)
		)
	)
	(wire
		(pts
			(xy 266.7 88.9) (xy 274.955 88.9)
		)
		(stroke
			(width 0)
			(type default)
		)
	)
	(polyline
		(pts
			(xy 229.235 53.975) (xy 229.235 55.245)
		)
		(stroke
			(width 0)
			(type dash)
		)
	)
	(polyline
		(pts
			(xy 156.21 85.09) (xy 122.555 85.09)
		)
		(stroke
			(width 0)
			(type dash)
		)
	)
	(wire
		(pts
			(xy 222.25 83.82) (xy 231.14 83.82)
		)
		(stroke
			(width 0)
			(type default)
		)
	)
	(polyline
		(pts
			(xy 249.555 51.435) (xy 220.345 51.435)
		)
		(stroke
			(width 0)
			(type dash)
		)
	)
	(wire
		(pts
			(xy 222.25 78.74) (xy 254 78.74)
		)
		(stroke
			(width 0)
			(type default)
		)
	)
	(wire
		(pts
			(xy 319.405 178.435) (xy 327.66 178.435)
		)
		(stroke
			(width 0)
			(type default)
		)
	)
	(wire
		(pts
			(xy 158.75 197.485) (xy 163.83 197.485)
		)
		(stroke
			(width 0)
			(type default)
		)
	)
	(wire
		(pts
			(xy 266.7 119.38) (xy 266.7 120.65)
		)
		(stroke
			(width 0)
			(type default)
		)
	)
	(wire
		(pts
			(xy 274.955 88.9) (xy 280.035 88.9)
		)
		(stroke
			(width 0)
			(type default)
		)
	)
	(wire
		(pts
			(xy 227.33 214.63) (xy 227.33 227.33)
		)
		(stroke
			(width 0)
			(type default)
		)
	)
	(wire
		(pts
			(xy 158.75 178.435) (xy 162.56 178.435)
		)
		(stroke
			(width 0)
			(type default)
		)
	)
	(wire
		(pts
			(xy 141.605 97.79) (xy 176.53 97.79)
		)
		(stroke
			(width 0)
			(type default)
		)
	)
	(wire
		(pts
			(xy 191.135 81.28) (xy 191.135 73.66)
		)
		(stroke
			(width 0)
			(type default)
		)
	)
	(wire
		(pts
			(xy 218.44 178.435) (xy 281.305 178.435)
		)
		(stroke
			(width 0)
			(type default)
		)
	)
	(wire
		(pts
			(xy 231.14 114.3) (xy 236.22 114.3)
		)
		(stroke
			(width 0)
			(type default)
		)
	)
	(wire
		(pts
			(xy 142.875 105.41) (xy 142.875 106.045)
		)
		(stroke
			(width 0)
			(type default)
		)
	)
	(wire
		(pts
			(xy 302.26 186.055) (xy 302.26 187.325)
		)
		(stroke
			(width 0)
			(type default)
		)
	)
	(wire
		(pts
			(xy 281.305 178.435) (xy 295.91 178.435)
		)
		(stroke
			(width 0)
			(type default)
		)
	)
	(wire
		(pts
			(xy 184.15 109.22) (xy 194.31 109.22)
		)
		(stroke
			(width 0)
			(type default)
		)
	)
	(wire
		(pts
			(xy 254 101.6) (xy 254 104.14)
		)
		(stroke
			(width 0)
			(type default)
		)
	)
	(wire
		(pts
			(xy 281.305 184.785) (xy 281.305 186.055)
		)
		(stroke
			(width 0)
			(type default)
		)
	)
	(wire
		(pts
			(xy 241.3 114.3) (xy 254 114.3)
		)
		(stroke
			(width 0)
			(type default)
		)
	)
	(wire
		(pts
			(xy 276.225 192.405) (xy 276.225 193.675)
		)
		(stroke
			(width 0)
			(type default)
		)
	)
	(wire
		(pts
			(xy 243.84 217.17) (xy 243.84 218.44)
		)
		(stroke
			(width 0)
			(type default)
		)
	)
	(wire
		(pts
			(xy 291.465 104.14) (xy 294.64 104.14)
		)
		(stroke
			(width 0)
			(type default)
		)
	)
	(wire
		(pts
			(xy 319.405 176.53) (xy 319.405 178.435)
		)
		(stroke
			(width 0)
			(type default)
		)
	)
	(polyline
		(pts
			(xy 220.345 66.675) (xy 249.555 66.675)
		)
		(stroke
			(width 0)
			(type dash)
		)
	)
	(wire
		(pts
			(xy 260.985 186.055) (xy 260.985 193.675)
		)
		(stroke
			(width 0)
			(type default)
		)
	)
	(wire
		(pts
			(xy 174.625 100.33) (xy 174.625 102.87)
		)
		(stroke
			(width 0)
			(type default)
		)
	)
	(wire
		(pts
			(xy 222.25 106.68) (xy 223.52 106.68)
		)
		(stroke
			(width 0)
			(type default)
		)
	)
	(wire
		(pts
			(xy 260.985 193.675) (xy 276.225 193.675)
		)
		(stroke
			(width 0)
			(type default)
		)
	)
	(wire
		(pts
			(xy 168.91 178.435) (xy 176.53 178.435)
		)
		(stroke
			(width 0)
			(type default)
		)
	)
	(wire
		(pts
			(xy 159.385 57.785) (xy 170.815 57.785)
		)
		(stroke
			(width 0)
			(type default)
		)
	)
	(wire
		(pts
			(xy 241.3 86.36) (xy 247.015 86.36)
		)
		(stroke
			(width 0)
			(type default)
		)
	)
	(wire
		(pts
			(xy 176.53 97.79) (xy 176.53 102.87)
		)
		(stroke
			(width 0)
			(type default)
		)
	)
	(wire
		(pts
			(xy 291.465 74.295) (xy 294.64 74.295)
		)
		(stroke
			(width 0)
			(type default)
		)
	)
	(wire
		(pts
			(xy 218.44 186.055) (xy 260.985 186.055)
		)
		(stroke
			(width 0)
			(type default)
		)
	)
	(wire
		(pts
			(xy 257.81 119.38) (xy 266.7 119.38)
		)
		(stroke
			(width 0)
			(type default)
		)
	)
	(wire
		(pts
			(xy 141.605 102.87) (xy 142.875 102.87)
		)
		(stroke
			(width 0)
			(type default)
		)
	)
	(wire
		(pts
			(xy 266.7 104.14) (xy 274.955 104.14)
		)
		(stroke
			(width 0)
			(type default)
		)
	)
	(wire
		(pts
			(xy 231.14 106.68) (xy 231.14 104.14)
		)
		(stroke
			(width 0)
			(type default)
		)
	)
	(polyline
		(pts
			(xy 156.21 74.93) (xy 156.21 85.09)
		)
		(stroke
			(width 0)
			(type dash)
		)
	)
	(wire
		(pts
			(xy 159.385 57.785) (xy 159.385 73.66)
		)
		(stroke
			(width 0)
			(type default)
		)
	)
	(polyline
		(pts
			(xy 220.345 64.135) (xy 249.555 64.135)
		)
		(stroke
			(width 0)
			(type dash)
		)
	)
	(wire
		(pts
			(xy 254 114.3) (xy 254 111.76)
		)
		(stroke
			(width 0)
			(type default)
		)
	)
	(wire
		(pts
			(xy 257.81 88.9) (xy 266.7 88.9)
		)
		(stroke
			(width 0)
			(type default)
		)
	)
	(wire
		(pts
			(xy 184.15 171.45) (xy 184.15 183.515)
		)
		(stroke
			(width 0)
			(type default)
		)
	)
	(wire
		(pts
			(xy 223.52 86.36) (xy 223.52 106.68)
		)
		(stroke
			(width 0)
			(type default)
		)
	)
	(wire
		(pts
			(xy 176.53 178.435) (xy 176.53 179.705)
		)
		(stroke
			(width 0)
			(type default)
		)
	)
	(wire
		(pts
			(xy 176.53 197.485) (xy 176.53 186.055)
		)
		(stroke
			(width 0)
			(type default)
		)
	)
	(wire
		(pts
			(xy 342.265 177.165) (xy 342.265 178.435)
		)
		(stroke
			(width 0)
			(type default)
		)
	)
	(wire
		(pts
			(xy 291.465 102.87) (xy 291.465 104.14)
		)
		(stroke
			(width 0)
			(type default)
		)
	)
	(wire
		(pts
			(xy 170.815 57.785) (xy 170.815 59.055)
		)
		(stroke
			(width 0)
			(type default)
		)
	)
	(wire
		(pts
			(xy 295.91 178.435) (xy 295.91 180.975)
		)
		(stroke
			(width 0)
			(type default)
		)
	)
	(wire
		(pts
			(xy 158.75 177.165) (xy 158.75 178.435)
		)
		(stroke
			(width 0)
			(type default)
		)
	)
	(wire
		(pts
			(xy 291.465 72.39) (xy 291.465 74.295)
		)
		(stroke
			(width 0)
			(type default)
		)
	)
	(wire
		(pts
			(xy 227.33 227.33) (xy 247.65 227.33)
		)
		(stroke
			(width 0)
			(type default)
		)
	)
	(wire
		(pts
			(xy 168.91 197.485) (xy 176.53 197.485)
		)
		(stroke
			(width 0)
			(type default)
		)
	)
	(wire
		(pts
			(xy 176.53 186.055) (xy 176.53 184.785)
		)
		(stroke
			(width 0)
			(type default)
		)
	)
	(wire
		(pts
			(xy 247.015 116.84) (xy 247.015 106.68)
		)
		(stroke
			(width 0)
			(type default)
		)
	)
	(wire
		(pts
			(xy 247.015 116.84) (xy 247.015 120.015)
		)
		(stroke
			(width 0)
			(type default)
		)
	)
	(wire
		(pts
			(xy 193.04 100.33) (xy 194.31 100.33)
		)
		(stroke
			(width 0)
			(type default)
		)
	)
	(wire
		(pts
			(xy 180.975 57.785) (xy 193.04 57.785)
		)
		(stroke
			(width 0)
			(type default)
		)
	)
	(wire
		(pts
			(xy 241.3 104.14) (xy 254 104.14)
		)
		(stroke
			(width 0)
			(type default)
		)
	)
	(wire
		(pts
			(xy 291.465 119.38) (xy 294.64 119.38)
		)
		(stroke
			(width 0)
			(type default)
		)
	)
	(polyline
		(pts
			(xy 220.345 61.595) (xy 249.555 61.595)
		)
		(stroke
			(width 0)
			(type dash)
		)
	)
	(wire
		(pts
			(xy 193.04 97.79) (xy 193.04 93.345)
		)
		(stroke
			(width 0)
			(type default)
		)
	)
	(wire
		(pts
			(xy 254 74.295) (xy 254 78.74)
		)
		(stroke
			(width 0)
			(type default)
		)
	)
	(wire
		(pts
			(xy 222.25 86.36) (xy 223.52 86.36)
		)
		(stroke
			(width 0)
			(type default)
		)
	)
	(wire
		(pts
			(xy 231.14 207.01) (xy 231.14 214.63)
		)
		(stroke
			(width 0)
			(type default)
		)
	)
	(wire
		(pts
			(xy 219.71 196.215) (xy 219.71 197.485)
		)
		(stroke
			(width 0)
			(type default)
		)
	)
	(wire
		(pts
			(xy 276.225 186.055) (xy 281.305 186.055)
		)
		(stroke
			(width 0)
			(type default)
		)
	)
	(wire
		(pts
			(xy 222.25 104.14) (xy 231.14 104.14)
		)
		(stroke
			(width 0)
			(type default)
		)
	)
	(wire
		(pts
			(xy 191.135 73.66) (xy 180.975 73.66)
		)
		(stroke
			(width 0)
			(type default)
		)
	)
	(wire
		(pts
			(xy 266.7 88.9) (xy 266.7 90.17)
		)
		(stroke
			(width 0)
			(type default)
		)
	)
	(wire
		(pts
			(xy 141.605 95.25) (xy 159.385 95.25)
		)
		(stroke
			(width 0)
			(type default)
		)
	)
	(wire
		(pts
			(xy 193.04 114.3) (xy 193.04 115.57)
		)
		(stroke
			(width 0)
			(type default)
		)
	)
	(wire
		(pts
			(xy 332.74 178.435) (xy 342.265 178.435)
		)
		(stroke
			(width 0)
			(type default)
		)
	)
	(wire
		(pts
			(xy 281.305 186.055) (xy 281.305 189.865)
		)
		(stroke
			(width 0)
			(type default)
		)
	)
	(wire
		(pts
			(xy 236.22 116.84) (xy 231.14 116.84)
		)
		(stroke
			(width 0)
			(type default)
		)
	)
	(polyline
		(pts
			(xy 122.555 74.93) (xy 122.555 85.09)
		)
		(stroke
			(width 0)
			(type dash)
		)
	)
	(wire
		(pts
			(xy 184.15 109.22) (xy 184.15 166.37)
		)
		(stroke
			(width 0)
			(type default)
		)
	)
	(wire
		(pts
			(xy 141.605 105.41) (xy 142.875 105.41)
		)
		(stroke
			(width 0)
			(type default)
		)
	)
	(wire
		(pts
			(xy 295.91 178.435) (xy 302.26 178.435)
		)
		(stroke
			(width 0)
			(type default)
		)
	)
	(wire
		(pts
			(xy 254 88.9) (xy 257.81 88.9)
		)
		(stroke
			(width 0)
			(type default)
		)
	)
	(wire
		(pts
			(xy 274.955 74.295) (xy 280.035 74.295)
		)
		(stroke
			(width 0)
			(type default)
		)
	)
	(wire
		(pts
			(xy 193.04 78.74) (xy 194.31 78.74)
		)
		(stroke
			(width 0)
			(type default)
		)
	)
	(wire
		(pts
			(xy 243.84 198.12) (xy 243.84 198.755)
		)
		(stroke
			(width 0)
			(type default)
		)
	)
	(wire
		(pts
			(xy 254 78.74) (xy 254 83.82)
		)
		(stroke
			(width 0)
			(type default)
		)
	)
	(wire
		(pts
			(xy 291.465 118.11) (xy 291.465 119.38)
		)
		(stroke
			(width 0)
			(type default)
		)
	)
	(wire
		(pts
			(xy 276.225 200.025) (xy 276.225 201.295)
		)
		(stroke
			(width 0)
			(type default)
		)
	)
	(wire
		(pts
			(xy 159.385 81.28) (xy 159.385 95.25)
		)
		(stroke
			(width 0)
			(type default)
		)
	)
	(wire
		(pts
			(xy 222.25 111.76) (xy 254 111.76)
		)
		(stroke
			(width 0)
			(type default)
		)
	)
	(bus
		(pts
			(xy 173.355 104.14) (xy 170.18 104.14)
		)
		(stroke
			(width 0)
			(type default)
		)
	)
	(wire
		(pts
			(xy 142.875 102.87) (xy 142.875 92.71)
		)
		(stroke
			(width 0)
			(type default)
		)
	)
	(wire
		(pts
			(xy 257.81 114.3) (xy 254 114.3)
		)
		(stroke
			(width 0)
			(type default)
		)
	)
	(wire
		(pts
			(xy 291.465 87.63) (xy 291.465 88.9)
		)
		(stroke
			(width 0)
			(type default)
		)
	)
	(wire
		(pts
			(xy 170.815 57.785) (xy 180.975 57.785)
		)
		(stroke
			(width 0)
			(type default)
		)
	)
	(wire
		(pts
			(xy 231.14 99.06) (xy 231.14 96.52)
		)
		(stroke
			(width 0)
			(type default)
		)
	)
	(wire
		(pts
			(xy 191.135 81.28) (xy 194.31 81.28)
		)
		(stroke
			(width 0)
			(type default)
		)
	)
	(wire
		(pts
			(xy 231.14 96.52) (xy 236.22 96.52)
		)
		(stroke
			(width 0)
			(type default)
		)
	)
	(polyline
		(pts
			(xy 234.315 53.975) (xy 234.315 66.675)
		)
		(stroke
			(width 0)
			(type dash)
		)
	)
	(polyline
		(pts
			(xy 239.395 53.975) (xy 239.395 66.675)
		)
		(stroke
			(width 0)
			(type dash)
		)
	)
	(polyline
		(pts
			(xy 249.555 66.675) (xy 249.555 61.595)
		)
		(stroke
			(width 0)
			(type dash)
		)
	)
	(wire
		(pts
			(xy 193.04 57.785) (xy 193.04 78.74)
		)
		(stroke
			(width 0)
			(type default)
		)
	)
	(label "FB1"
		(at 228.6 83.82 180)
		(effects
			(font
				(size 1.27 1.27)
			)
			(justify right bottom)
		)
	)
	(label "VOUT"
		(at 239.395 178.435 0)
		(effects
			(font
				(size 1.27 1.27)
			)
			(justify left bottom)
		)
	)
	(label "FB2"
		(at 228.6 96.52 180)
		(effects
			(font
				(size 1.27 1.27)
			)
			(justify right bottom)
		)
	)
	(label "VOUT3"
		(at 259.08 104.14 0)
		(effects
			(font
				(size 1.27 1.27)
			)
			(justify left bottom)
		)
	)
	(label "VOUT2"
		(at 259.08 88.9 0)
		(effects
			(font
				(size 1.27 1.27)
			)
			(justify left bottom)
		)
	)
	(label "VOUT4"
		(at 259.08 119.38 0)
		(effects
			(font
				(size 1.27 1.27)
			)
			(justify left bottom)
		)
	)
	(label "I2C.SCL"
		(at 179.07 100.33 0)
		(effects
			(font
				(size 1.27 1.27)
			)
			(justify left bottom)
		)
	)
	(label "FB4"
		(at 228.6 114.3 180)
		(effects
			(font
				(size 1.27 1.27)
			)
			(justify right bottom)
		)
	)
	(label "FB3"
		(at 228.6 104.14 180)
		(effects
			(font
				(size 1.27 1.27)
			)
			(justify right bottom)
		)
	)
	(label "I2C.SDA"
		(at 179.07 97.79 0)
		(effects
			(font
				(size 1.27 1.27)
			)
			(justify left bottom)
		)
	)
	(label "3.3V_QWIIC"
		(at 146.05 95.25 0)
		(effects
			(font
				(size 1.27 1.27)
			)
			(justify left bottom)
		)
	)
	(label "VOUT1"
		(at 259.08 74.295 0)
		(effects
			(font
				(size 1.27 1.27)
			)
			(justify left bottom)
		)
	)
	(label "DCDC_PWRGD"
		(at 184.15 153.035 90)
		(effects
			(font
				(size 1.27 1.27)
			)
			(justify left bottom)
		)
	)
	(hierarchical_label "PWRGD"
		(shape output)
		(at 247.65 227.33 0)
		(effects
			(font
				(size 1.27 1.27)
			)
			(justify left)
		)
	)
	(hierarchical_label "PWR_EN"
		(shape input)
		(at 158.75 197.485 180)
		(effects
			(font
				(size 1.27 1.27)
			)
			(justify right)
		)
	)
	(hierarchical_label "PWR_EN"
		(shape input)
		(at 170.18 88.9 180)
		(effects
			(font
				(size 1.27 1.27)
			)
			(justify right)
		)
	)
	(hierarchical_label "I2C{SDA,SCL}"
		(shape bidirectional)
		(at 170.18 104.14 180)
		(effects
			(font
				(size 1.27 1.27)
			)
			(justify right)
		)
	)
	(symbol
		(lib_id "antmicropower:+1V05")
		(at 291.465 102.87 0)
		(unit 1)
		(exclude_from_sim no)
		(in_bom yes)
		(on_board yes)
		(dnp no)
		(fields_autoplaced yes)
		(property "Reference" "#PWR0149"
			(at 291.465 106.68 0)
			(effects
				(font
					(size 1.27 1.27)
				)
				(hide yes)
			)
		)
		(property "Value" "+1V05"
			(at 291.465 97.79 0)
			(effects
				(font
					(size 1.27 1.27)
				)
			)
		)
		(property "Footprint" ""
			(at 291.465 102.87 0)
			(effects
				(font
					(size 1.27 1.27)
				)
				(hide yes)
			)
		)
		(property "Datasheet" ""
			(at 291.465 102.87 0)
			(effects
				(font
					(size 1.27 1.27)
				)
				(hide yes)
			)
		)
		(property "Description" ""
			(at 291.465 102.87 0)
			(effects
				(font
					(size 1.27 1.27)
				)
			)
		)
		(pin "1"
		)
		(instances
			(project ""
				(path ""
					(reference "#PWR0149")
					(unit 1)
				)
			)
		)
	)
	(symbol
		(lib_id "antmicroCapacitors0402:C_4u7_0402")
		(at 168.91 184.785 90)
		(unit 1)
		(exclude_from_sim no)
		(in_bom yes)
		(on_board yes)
		(dnp no)
		(property "Reference" "C9"
			(at 169.545 180.34 90)
			(effects
				(font
					(size 1.27 1.27)
					(thickness 0.15)
				)
				(justify right)
			)
		)
		(property "Value" "C_4u7_0402"
			(at 179.07 164.465 0)
			(effects
				(font
					(size 1.27 1.27)
					(thickness 0.15)
				)
				(justify left bottom)
				(hide yes)
			)
		)
		(property "Footprint" "antmicro-footprints:C_0402_1005Metric"
			(at 181.61 164.465 0)
			(effects
				(font
					(size 1.27 1.27)
					(thickness 0.15)
				)
				(justify left bottom)
				(hide yes)
			)
		)
		(property "Datasheet" "https://www.murata.com/products/productdetail?partno=GRM155R61A475MEAA%23"
			(at 184.15 164.465 0)
			(effects
				(font
					(size 1.27 1.27)
					(thickness 0.15)
				)
				(justify left bottom)
				(hide yes)
			)
		)
		(property "Description" ""
			(at 168.91 184.785 0)
			(effects
				(font
					(size 1.27 1.27)
				)
			)
		)
		(property "MPN" "GRM155R61A475MEAAD"
			(at 186.69 164.465 0)
			(effects
				(font
					(size 1.27 1.27)
					(thickness 0.15)
				)
				(justify left bottom)
				(hide yes)
			)
		)
		(property "Manufacturer" "Murata"
			(at 189.23 164.465 0)
			(effects
				(font
					(size 1.27 1.27)
					(thickness 0.15)
				)
				(justify left bottom)
				(hide yes)
			)
		)
		(property "License" "Apache-2.0"
			(at 191.77 164.465 0)
			(effects
				(font
					(size 1.27 1.27)
					(thickness 0.15)
				)
				(justify left bottom)
				(hide yes)
			)
		)
		(property "Author" "Antmicro"
			(at 194.31 164.465 0)
			(effects
				(font
					(size 1.27 1.27)
					(thickness 0.15)
				)
				(justify left bottom)
				(hide yes)
			)
		)
		(property "Val" "4u7"
			(at 169.545 184.15 90)
			(effects
				(font
					(size 1.27 1.27)
					(thickness 0.15)
				)
				(justify right)
			)
		)
		(property "Voltage" ""
			(at 196.85 164.465 0)
			(effects
				(font
					(size 1.27 1.27)
				)
				(justify left bottom)
				(hide yes)
			)
		)
		(property "Dielectric" ""
			(at 199.39 164.465 0)
			(effects
				(font
					(size 1.27 1.27)
				)
				(justify left bottom)
				(hide yes)
			)
		)
		(pin "1"
		)
		(pin "2"
		)
		(instances
			(project ""
				(path ""
					(reference "C9")
					(unit 1)
				)
			)
		)
	)
	(symbol
		(lib_id "antmicroTestPoints:TP_0.75mm_SMD")
		(at 274.955 86.995 90)
		(unit 1)
		(exclude_from_sim no)
		(in_bom yes)
		(on_board yes)
		(dnp no)
		(property "Reference" "TP5"
			(at 272.415 83.185 0)
			(effects
				(font
					(size 1.27 1.27)
					(thickness 0.15)
				)
			)
		)
		(property "Value" "TP_0.75mm_SMD"
			(at 278.765 76.2 0)
			(effects
				(font
					(size 1.27 1.27)
					(thickness 0.15)
				)
				(justify left bottom)
				(hide yes)
			)
		)
		(property "Footprint" "antmicro-footprints:TP_SMD_0.75mm"
			(at 281.305 76.2 0)
			(effects
				(font
					(size 1.27 1.27)
					(thickness 0.15)
				)
				(justify left bottom)
				(hide yes)
			)
		)
		(property "Datasheet" ""
			(at 287.655 69.215 0)
			(effects
				(font
					(size 1.27 1.27)
					(thickness 0.15)
				)
				(justify left bottom)
				(hide yes)
			)
		)
		(property "Description" ""
			(at 274.955 86.995 0)
			(effects
				(font
					(size 1.27 1.27)
				)
			)
		)
		(property "MPN" ""
			(at 286.385 76.2 0)
			(effects
				(font
					(size 1.27 1.27)
					(thickness 0.15)
				)
				(justify left bottom)
				(hide yes)
			)
		)
		(property "Manufacturer" ""
			(at 281.305 76.2 0)
			(effects
				(font
					(size 1.27 1.27)
					(thickness 0.15)
				)
				(justify left bottom)
				(hide yes)
			)
		)
		(property "Author" "Antmicro"
			(at 283.845 76.2 0)
			(effects
				(font
					(size 1.27 1.27)
					(thickness 0.15)
				)
				(justify left bottom)
				(hide yes)
			)
		)
		(property "License" "Apache-2.0"
			(at 286.385 76.2 0)
			(effects
				(font
					(size 1.27 1.27)
					(thickness 0.15)
				)
				(justify left bottom)
				(hide yes)
			)
		)
		(pin "1"
		)
		(instances
			(project ""
				(path ""
					(reference "TP5")
					(unit 1)
				)
			)
		)
	)
	(symbol
		(lib_id "antmicroResistors0402:R_3k9_0402")
		(at 276.225 200.025 90)
		(unit 1)
		(exclude_from_sim no)
		(in_bom yes)
		(on_board yes)
		(dnp no)
		(fields_autoplaced yes)
		(property "Reference" "R50"
			(at 273.685 196.2149 90)
			(effects
				(font
					(size 1.27 1.27)
					(thickness 0.15)
				)
				(justify left)
			)
		)
		(property "Value" "R_3k9_0402"
			(at 288.925 179.705 0)
			(effects
				(font
					(size 1.27 1.27)
					(thickness 0.15)
				)
				(justify left bottom)
				(hide yes)
			)
		)
		(property "Footprint" "antmicro-footprints:R_0402_1005Metric"
			(at 291.465 179.705 0)
			(effects
				(font
					(size 1.27 1.27)
					(thickness 0.15)
				)
				(justify left bottom)
				(hide yes)
			)
		)
		(property "Datasheet" "https://www.bourns.com/docs/product-datasheets/cr.pdf"
			(at 294.005 179.705 0)
			(effects
				(font
					(size 1.27 1.27)
					(thickness 0.15)
				)
				(justify left bottom)
				(hide yes)
			)
		)
		(property "Description" ""
			(at 276.225 200.025 0)
			(effects
				(font
					(size 1.27 1.27)
				)
			)
		)
		(property "MPN" "CR0402-FX-3901GLF"
			(at 296.545 179.705 0)
			(effects
				(font
					(size 1.27 1.27)
					(thickness 0.15)
				)
				(justify left bottom)
				(hide yes)
			)
		)
		(property "Manufacturer" "Bourns"
			(at 299.085 179.705 0)
			(effects
				(font
					(size 1.27 1.27)
					(thickness 0.15)
				)
				(justify left bottom)
				(hide yes)
			)
		)
		(property "License" "Apache-2.0"
			(at 301.625 179.705 0)
			(effects
				(font
					(size 1.27 1.27)
					(thickness 0.15)
				)
				(justify left bottom)
				(hide yes)
			)
		)
		(property "Author" "Antmicro"
			(at 304.165 179.705 0)
			(effects
				(font
					(size 1.27 1.27)
					(thickness 0.15)
				)
				(justify left bottom)
				(hide yes)
			)
		)
		(property "Val" "3k9"
			(at 273.685 198.7549 90)
			(effects
				(font
					(size 1.27 1.27)
					(thickness 0.15)
				)
				(justify left)
			)
		)
		(property "Tolerance" "1%"
			(at 286.385 179.705 0)
			(effects
				(font
					(size 1.27 1.27)
				)
				(justify left bottom)
				(hide yes)
			)
		)
		(pin "1"
		)
		(pin "2"
		)
		(instances
			(project ""
				(path ""
					(reference "R50")
					(unit 1)
				)
			)
		)
	)
	(symbol
		(lib_id "antmicropower:PWR_FLAG")
		(at 294.64 119.38 270)
		(unit 1)
		(exclude_from_sim no)
		(in_bom yes)
		(on_board yes)
		(dnp no)
		(property "Reference" "#FLG0102"
			(at 296.545 119.38 0)
			(effects
				(font
					(size 1.27 1.27)
				)
				(hide yes)
			)
		)
		(property "Value" "PWR_FLAG"
			(at 297.815 119.38 90)
			(effects
				(font
					(size 1.27 1.27)
				)
				(justify left)
			)
		)
		(property "Footprint" ""
			(at 294.64 119.38 0)
			(effects
				(font
					(size 1.27 1.27)
				)
				(hide yes)
			)
		)
		(property "Datasheet" ""
			(at 294.64 119.38 0)
			(effects
				(font
					(size 1.27 1.27)
				)
				(hide yes)
			)
		)
		(property "Description" ""
			(at 294.64 119.38 0)
			(effects
				(font
					(size 1.27 1.27)
				)
			)
		)
		(pin "1"
		)
		(instances
			(project ""
				(path ""
					(reference "#FLG0102")
					(unit 1)
				)
			)
		)
	)
	(symbol
		(lib_id "antmicropower:GND")
		(at 189.23 197.485 0)
		(unit 1)
		(exclude_from_sim no)
		(in_bom yes)
		(on_board yes)
		(dnp no)
		(property "Reference" "#PWR0166"
			(at 198.12 200.025 0)
			(effects
				(font
					(size 1.27 1.27)
					(thickness 0.15)
				)
				(justify left bottom)
				(hide yes)
			)
		)
		(property "Value" "GND"
			(at 189.23 201.295 0)
			(effects
				(font
					(size 1.27 1.27)
					(thickness 0.15)
				)
			)
		)
		(property "Footprint" ""
			(at 198.12 205.105 0)
			(effects
				(font
					(size 1.27 1.27)
					(thickness 0.15)
				)
				(justify left bottom)
				(hide yes)
			)
		)
		(property "Datasheet" ""
			(at 198.12 210.185 0)
			(effects
				(font
					(size 1.27 1.27)
					(thickness 0.15)
				)
				(justify left bottom)
				(hide yes)
			)
		)
		(property "Description" ""
			(at 189.23 197.485 0)
			(effects
				(font
					(size 1.27 1.27)
				)
			)
		)
		(property "Author" "Antmicro"
			(at 198.12 205.105 0)
			(effects
				(font
					(size 1.27 1.27)
					(thickness 0.15)
				)
				(justify left bottom)
				(hide yes)
			)
		)
		(property "License" "Apache-2.0"
			(at 198.12 207.645 0)
			(effects
				(font
					(size 1.27 1.27)
					(thickness 0.15)
				)
				(justify left bottom)
				(hide yes)
			)
		)
		(pin "1"
		)
		(instances
			(project ""
				(path ""
					(reference "#PWR0166")
					(unit 1)
				)
			)
		)
	)
	(symbol
		(lib_id "antmicroCapacitors0603:C_22u_0603")
		(at 266.7 95.25 90)
		(unit 1)
		(exclude_from_sim no)
		(in_bom yes)
		(on_board yes)
		(dnp no)
		(property "Reference" "C17"
			(at 267.335 90.805 90)
			(effects
				(font
					(size 1.27 1.27)
					(thickness 0.15)
				)
				(justify right)
			)
		)
		(property "Value" "C_22u_0603"
			(at 276.86 74.93 0)
			(effects
				(font
					(size 1.27 1.27)
					(thickness 0.15)
				)
				(justify left bottom)
				(hide yes)
			)
		)
		(property "Footprint" "antmicro-footprints:C_0603_1608Metric"
			(at 279.4 74.93 0)
			(effects
				(font
					(size 1.27 1.27)
					(thickness 0.15)
				)
				(justify left bottom)
				(hide yes)
			)
		)
		(property "Datasheet" "https://www.murata.com/products/productdetail?partno=GRM188R60J226MEA0%23"
			(at 281.94 74.93 0)
			(effects
				(font
					(size 1.27 1.27)
					(thickness 0.15)
				)
				(justify left bottom)
				(hide yes)
			)
		)
		(property "Description" ""
			(at 266.7 95.25 0)
			(effects
				(font
					(size 1.27 1.27)
				)
			)
		)
		(property "MPN" "GRM188R60J226MEA0D"
			(at 284.48 74.93 0)
			(effects
				(font
					(size 1.27 1.27)
					(thickness 0.15)
				)
				(justify left bottom)
				(hide yes)
			)
		)
		(property "Manufacturer" "Murata"
			(at 287.02 74.93 0)
			(effects
				(font
					(size 1.27 1.27)
					(thickness 0.15)
				)
				(justify left bottom)
				(hide yes)
			)
		)
		(property "License" "Apache-2.0"
			(at 289.56 74.93 0)
			(effects
				(font
					(size 1.27 1.27)
					(thickness 0.15)
				)
				(justify left bottom)
				(hide yes)
			)
		)
		(property "Author" "Antmicro"
			(at 292.1 74.93 0)
			(effects
				(font
					(size 1.27 1.27)
					(thickness 0.15)
				)
				(justify left bottom)
				(hide yes)
			)
		)
		(property "Val" "22u"
			(at 267.335 94.615 90)
			(effects
				(font
					(size 1.27 1.27)
					(thickness 0.15)
				)
				(justify right)
			)
		)
		(property "Voltage" ""
			(at 294.64 74.93 0)
			(effects
				(font
					(size 1.27 1.27)
				)
				(justify left bottom)
				(hide yes)
			)
		)
		(property "Dielectric" ""
			(at 297.18 74.93 0)
			(effects
				(font
					(size 1.27 1.27)
				)
				(justify left bottom)
				(hide yes)
			)
		)
		(pin "1"
		)
		(pin "2"
		)
		(instances
			(project ""
				(path ""
					(reference "C17")
					(unit 1)
				)
			)
		)
	)
	(symbol
		(lib_id "antmicroCapacitors0402:C_10n_0402")
		(at 219.71 202.565 90)
		(unit 1)
		(exclude_from_sim no)
		(in_bom yes)
		(on_board yes)
		(dnp no)
		(property "Reference" "C13"
			(at 220.345 198.12 90)
			(effects
				(font
					(size 1.27 1.27)
					(thickness 0.15)
				)
				(justify right)
			)
		)
		(property "Value" "C_10n_0402"
			(at 229.87 182.245 0)
			(effects
				(font
					(size 1.27 1.27)
					(thickness 0.15)
				)
				(justify left bottom)
				(hide yes)
			)
		)
		(property "Footprint" "antmicro-footprints:C_0402_1005Metric"
			(at 232.41 182.245 0)
			(effects
				(font
					(size 1.27 1.27)
					(thickness 0.15)
				)
				(justify left bottom)
				(hide yes)
			)
		)
		(property "Datasheet" "https://www.murata.com/products/productdetail?partno=GRM155R71H103KA88%23"
			(at 234.95 182.245 0)
			(effects
				(font
					(size 1.27 1.27)
					(thickness 0.15)
				)
				(justify left bottom)
				(hide yes)
			)
		)
		(property "Description" ""
			(at 219.71 202.565 0)
			(effects
				(font
					(size 1.27 1.27)
				)
			)
		)
		(property "MPN" "GRM155R71H103KA88D"
			(at 237.49 182.245 0)
			(effects
				(font
					(size 1.27 1.27)
					(thickness 0.15)
				)
				(justify left bottom)
				(hide yes)
			)
		)
		(property "Manufacturer" "Murata"
			(at 240.03 182.245 0)
			(effects
				(font
					(size 1.27 1.27)
					(thickness 0.15)
				)
				(justify left bottom)
				(hide yes)
			)
		)
		(property "License" "Apache-2.0"
			(at 242.57 182.245 0)
			(effects
				(font
					(size 1.27 1.27)
					(thickness 0.15)
				)
				(justify left bottom)
				(hide yes)
			)
		)
		(property "Author" "Antmicro"
			(at 245.11 182.245 0)
			(effects
				(font
					(size 1.27 1.27)
					(thickness 0.15)
				)
				(justify left bottom)
				(hide yes)
			)
		)
		(property "Val" "10n"
			(at 220.345 201.93 90)
			(effects
				(font
					(size 1.27 1.27)
					(thickness 0.15)
				)
				(justify right)
			)
		)
		(property "Voltage" "50V"
			(at 247.65 182.245 0)
			(effects
				(font
					(size 1.27 1.27)
				)
				(justify left bottom)
				(hide yes)
			)
		)
		(property "Dielectric" "X7R"
			(at 250.19 182.245 0)
			(effects
				(font
					(size 1.27 1.27)
				)
				(justify left bottom)
				(hide yes)
			)
		)
		(pin "1"
		)
		(pin "2"
		)
		(instances
			(project ""
				(path ""
					(reference "C13")
					(unit 1)
				)
			)
		)
	)
	(symbol
		(lib_id "antmicroPMICVoltageRegulatorsDCDCSwitchingRegulators:MPM54304GMN-0001")
		(at 194.31 78.74 0)
		(unit 1)
		(exclude_from_sim no)
		(in_bom yes)
		(on_board yes)
		(dnp no)
		(property "Reference" "U8"
			(at 208.28 72.39 0)
			(effects
				(font
					(size 1.27 1.27)
					(thickness 0.15)
				)
			)
		)
		(property "Value" "MPM54304GMN-0001"
			(at 208.28 74.93 0)
			(effects
				(font
					(size 1.27 1.27)
					(thickness 0.15)
				)
			)
		)
		(property "Footprint" "antmicro-footprints:LGA-33_7x7mm_P0.65mm"
			(at 241.3 86.36 0)
			(effects
				(font
					(size 1.27 1.27)
					(thickness 0.15)
				)
				(justify left bottom)
				(hide yes)
			)
		)
		(property "Datasheet" "https://www.monolithicpower.com/en/documentview/productdocument/index/version/2/document_type/Datasheet/lang/en/sku/MPM54304/document_id/4982/"
			(at 241.3 88.9 0)
			(effects
				(font
					(size 1.27 1.27)
					(thickness 0.15)
				)
				(justify left bottom)
				(hide yes)
			)
		)
		(property "Description" ""
			(at 194.31 78.74 0)
			(effects
				(font
					(size 1.27 1.27)
				)
			)
		)
		(property "MPN" "MPM54304GMN-0001"
			(at 241.3 91.44 0)
			(effects
				(font
					(size 1.27 1.27)
				)
				(justify left bottom)
				(hide yes)
			)
		)
		(property "Manufacturer" "Monolithic Power Systems"
			(at 241.3 93.98 0)
			(effects
				(font
					(size 1.27 1.27)
				)
				(justify left bottom)
				(hide yes)
			)
		)
		(property "Author" "Antmicro"
			(at 241.3 96.52 0)
			(effects
				(font
					(size 1.27 1.27)
				)
				(justify left bottom)
				(hide yes)
			)
		)
		(property "License" "Apache-2.0"
			(at 241.3 99.06 0)
			(effects
				(font
					(size 1.27 1.27)
				)
				(justify left bottom)
				(hide yes)
			)
		)
		(pin "1"
		)
		(pin "10"
		)
		(pin "11"
		)
		(pin "12"
		)
		(pin "13"
		)
		(pin "14"
		)
		(pin "15"
		)
		(pin "16"
		)
		(pin "17"
		)
		(pin "18"
		)
		(pin "19"
		)
		(pin "2"
		)
		(pin "20"
		)
		(pin "21"
		)
		(pin "22"
		)
		(pin "23"
		)
		(pin "24"
		)
		(pin "25"
		)
		(pin "26"
		)
		(pin "27"
		)
		(pin "28"
		)
		(pin "29"
		)
		(pin "3"
		)
		(pin "30"
		)
		(pin "31"
		)
		(pin "32"
		)
		(pin "33"
		)
		(pin "4"
		)
		(pin "5"
		)
		(pin "6"
		)
		(pin "7"
		)
		(pin "8"
		)
		(pin "9"
		)
		(instances
			(project ""
				(path ""
					(reference "U8")
					(unit 1)
				)
			)
		)
	)
	(symbol
		(lib_id "antmicropower:GND")
		(at 223.52 120.015 0)
		(unit 1)
		(exclude_from_sim no)
		(in_bom yes)
		(on_board yes)
		(dnp no)
		(property "Reference" "#PWR0221"
			(at 223.52 126.365 0)
			(effects
				(font
					(size 1.27 1.27)
				)
				(hide yes)
			)
		)
		(property "Value" "GND"
			(at 223.52 123.825 0)
			(effects
				(font
					(size 1.27 1.27)
				)
			)
		)
		(property "Footprint" ""
			(at 232.41 127.635 0)
			(effects
				(font
					(size 1.27 1.27)
					(thickness 0.15)
				)
				(justify left bottom)
				(hide yes)
			)
		)
		(property "Datasheet" ""
			(at 232.41 132.715 0)
			(effects
				(font
					(size 1.27 1.27)
					(thickness 0.15)
				)
				(justify left bottom)
				(hide yes)
			)
		)
		(property "Description" ""
			(at 223.52 120.015 0)
			(effects
				(font
					(size 1.27 1.27)
				)
			)
		)
		(property "Author" "Antmicro"
			(at 232.41 127.635 0)
			(effects
				(font
					(size 1.27 1.27)
					(thickness 0.15)
				)
				(justify left bottom)
				(hide yes)
			)
		)
		(property "License" "Apache-2.0"
			(at 232.41 130.175 0)
			(effects
				(font
					(size 1.27 1.27)
					(thickness 0.15)
				)
				(justify left bottom)
				(hide yes)
			)
		)
		(pin "1"
		)
		(instances
			(project ""
				(path ""
					(reference "#PWR0221")
					(unit 1)
				)
			)
		)
	)
	(symbol
		(lib_id "antmicroCapacitorsmisc:C_22u_25V_0805")
		(at 170.815 64.135 90)
		(unit 1)
		(exclude_from_sim no)
		(in_bom yes)
		(on_board yes)
		(dnp no)
		(property "Reference" "C10"
			(at 171.45 59.69 90)
			(effects
				(font
					(size 1.27 1.27)
					(thickness 0.15)
				)
				(justify right)
			)
		)
		(property "Value" "C_22u_25V_0805"
			(at 180.975 43.815 0)
			(effects
				(font
					(size 1.27 1.27)
					(thickness 0.15)
				)
				(justify left bottom)
				(hide yes)
			)
		)
		(property "Footprint" "antmicro-footprints:C_0805_2012Metric"
			(at 183.515 43.815 0)
			(effects
				(font
					(size 1.27 1.27)
					(thickness 0.15)
				)
				(justify left bottom)
				(hide yes)
			)
		)
		(property "Datasheet" "https://product.samsungsem.com/mlcc/CL21A226MAYNNN.do"
			(at 186.055 43.815 0)
			(effects
				(font
					(size 1.27 1.27)
					(thickness 0.15)
				)
				(justify left bottom)
				(hide yes)
			)
		)
		(property "Description" ""
			(at 170.815 64.135 0)
			(effects
				(font
					(size 1.27 1.27)
				)
			)
		)
		(property "MPN" "CL21A226MAYNNNE"
			(at 188.595 43.815 0)
			(effects
				(font
					(size 1.27 1.27)
					(thickness 0.15)
				)
				(justify left bottom)
				(hide yes)
			)
		)
		(property "Manufacturer" "Samsung Electro-Mechanics"
			(at 191.135 43.815 0)
			(effects
				(font
					(size 1.27 1.27)
					(thickness 0.15)
				)
				(justify left bottom)
				(hide yes)
			)
		)
		(property "License" "Apache-2.0"
			(at 193.675 43.815 0)
			(effects
				(font
					(size 1.27 1.27)
					(thickness 0.15)
				)
				(justify left bottom)
				(hide yes)
			)
		)
		(property "Author" "Antmicro"
			(at 196.215 43.815 0)
			(effects
				(font
					(size 1.27 1.27)
					(thickness 0.15)
				)
				(justify left bottom)
				(hide yes)
			)
		)
		(property "Val" "22u_25V"
			(at 171.45 63.5 90)
			(effects
				(font
					(size 1.27 1.27)
					(thickness 0.15)
				)
				(justify right)
			)
		)
		(property "Voltage" ""
			(at 198.755 43.815 0)
			(effects
				(font
					(size 1.27 1.27)
				)
				(justify left bottom)
				(hide yes)
			)
		)
		(property "Dielectric" ""
			(at 201.295 43.815 0)
			(effects
				(font
					(size 1.27 1.27)
				)
				(justify left bottom)
				(hide yes)
			)
		)
		(pin "1"
		)
		(pin "2"
		)
		(instances
			(project ""
				(path ""
					(reference "C10")
					(unit 1)
				)
			)
		)
	)
	(symbol
		(lib_id "antmicroTestPoints:TP_1mm_SMD")
		(at 191.135 103.505 0)
		(mirror y)
		(unit 1)
		(exclude_from_sim no)
		(in_bom yes)
		(on_board yes)
		(dnp no)
		(property "Reference" "TP3"
			(at 186.69 103.505 0)
			(effects
				(font
					(size 1.27 1.27)
					(thickness 0.15)
				)
				(justify left)
			)
		)
		(property "Value" "TP_1mm_SMD"
			(at 175.895 111.125 0)
			(effects
				(font
					(size 1.27 1.27)
					(thickness 0.15)
				)
				(justify left bottom)
				(hide yes)
			)
		)
		(property "Footprint" "antmicro-footprints:TP_SMD_1mm"
			(at 175.895 113.665 0)
			(effects
				(font
					(size 1.27 1.27)
					(thickness 0.15)
				)
				(justify left bottom)
				(hide yes)
			)
		)
		(property "Datasheet" ""
			(at 173.355 116.205 0)
			(effects
				(font
					(size 1.27 1.27)
					(thickness 0.15)
				)
				(justify left bottom)
				(hide yes)
			)
		)
		(property "Description" ""
			(at 191.135 103.505 0)
			(effects
				(font
					(size 1.27 1.27)
				)
			)
		)
		(property "MPN" ""
			(at 191.135 103.505 0)
			(effects
				(font
					(size 1.27 1.27)
				)
				(hide yes)
			)
		)
		(property "Manufacturer" ""
			(at 191.135 103.505 0)
			(effects
				(font
					(size 1.27 1.27)
				)
				(hide yes)
			)
		)
		(property "Author" "Antmicro"
			(at 175.895 118.745 0)
			(effects
				(font
					(size 1.27 1.27)
					(thickness 0.15)
				)
				(justify left bottom)
				(hide yes)
			)
		)
		(property "License" "Apache-2.0"
			(at 175.895 121.285 0)
			(effects
				(font
					(size 1.27 1.27)
					(thickness 0.15)
				)
				(justify left bottom)
				(hide yes)
			)
		)
		(pin "1"
		)
		(instances
			(project ""
				(path ""
					(reference "TP3")
					(unit 1)
				)
			)
		)
	)
	(symbol
		(lib_id "antmicroPMICVoltageRegulatorsLinear:LT3033EUDC_QFN")
		(at 198.12 178.435 0)
		(unit 1)
		(exclude_from_sim no)
		(in_bom yes)
		(on_board yes)
		(dnp no)
		(fields_autoplaced yes)
		(property "Reference" "U9"
			(at 208.28 170.18 0)
			(effects
				(font
					(size 1.27 1.27)
					(thickness 0.15)
				)
			)
		)
		(property "Value" "LT3033EUDC_QFN"
			(at 233.68 186.055 0)
			(effects
				(font
					(size 1.27 1.27)
					(thickness 0.15)
				)
				(justify left bottom)
				(hide yes)
			)
		)
		(property "Footprint" "antmicro-footprints:QFN-20-4EP_3x4x0.75mm_P0.5mm_Layout4x6_LT3033"
			(at 233.68 188.595 0)
			(effects
				(font
					(size 1.27 1.27)
					(thickness 0.15)
				)
				(justify left bottom)
				(hide yes)
			)
		)
		(property "Datasheet" "https://www.analog.com/media/en/technical-documentation/data-sheets/LT3033.pdf"
			(at 233.68 191.135 0)
			(effects
				(font
					(size 1.27 1.27)
					(thickness 0.15)
				)
				(justify left bottom)
				(hide yes)
			)
		)
		(property "Description" ""
			(at 198.12 178.435 0)
			(effects
				(font
					(size 1.27 1.27)
				)
			)
		)
		(property "MPN" "LT3033EUDC#PBF"
			(at 208.28 172.72 0)
			(effects
				(font
					(size 1.27 1.27)
					(thickness 0.15)
				)
			)
		)
		(property "Manufacturer" "Analog Devices"
			(at 233.68 193.675 0)
			(effects
				(font
					(size 1.27 1.27)
					(thickness 0.15)
				)
				(justify left bottom)
				(hide yes)
			)
		)
		(property "Author" "Antmicro"
			(at 233.68 196.215 0)
			(effects
				(font
					(size 1.27 1.27)
					(thickness 0.15)
				)
				(justify left bottom)
				(hide yes)
			)
		)
		(property "License" "Apache-2.0"
			(at 233.68 198.755 0)
			(effects
				(font
					(size 1.27 1.27)
					(thickness 0.15)
				)
				(justify left bottom)
				(hide yes)
			)
		)
		(pin "1"
		)
		(pin "10"
		)
		(pin "11"
		)
		(pin "12"
		)
		(pin "13"
		)
		(pin "14"
		)
		(pin "15"
		)
		(pin "16"
		)
		(pin "17"
		)
		(pin "18"
		)
		(pin "19"
		)
		(pin "2"
		)
		(pin "20"
		)
		(pin "21"
		)
		(pin "22"
		)
		(pin "23"
		)
		(pin "24"
		)
		(pin "3"
		)
		(pin "4"
		)
		(pin "5"
		)
		(pin "6"
		)
		(pin "7"
		)
		(pin "8"
		)
		(pin "9"
		)
		(instances
			(project ""
				(path ""
					(reference "U9")
					(unit 1)
				)
			)
		)
	)
	(symbol
		(lib_id "antmicroResistors0402:R_49k9_0402")
		(at 236.22 86.36 0)
		(unit 1)
		(exclude_from_sim no)
		(in_bom yes)
		(on_board yes)
		(dnp no)
		(property "Reference" "R34"
			(at 234.95 85.09 0)
			(effects
				(font
					(size 1.27 1.27)
					(thickness 0.15)
				)
			)
		)
		(property "Value" "R_49k9_0402"
			(at 256.54 99.06 0)
			(effects
				(font
					(size 1.27 1.27)
					(thickness 0.15)
				)
				(justify left bottom)
				(hide yes)
			)
		)
		(property "Footprint" "antmicro-footprints:R_0402_1005Metric"
			(at 256.54 101.6 0)
			(effects
				(font
					(size 1.27 1.27)
					(thickness 0.15)
				)
				(justify left bottom)
				(hide yes)
			)
		)
		(property "Datasheet" "https://www.bourns.com/docs/product-datasheets/cr.pdf"
			(at 256.54 104.14 0)
			(effects
				(font
					(size 1.27 1.27)
					(thickness 0.15)
				)
				(justify left bottom)
				(hide yes)
			)
		)
		(property "Description" ""
			(at 236.22 86.36 0)
			(effects
				(font
					(size 1.27 1.27)
				)
			)
		)
		(property "MPN" "CR0402-FX-4992GLF"
			(at 256.54 106.68 0)
			(effects
				(font
					(size 1.27 1.27)
					(thickness 0.15)
				)
				(justify left bottom)
				(hide yes)
			)
		)
		(property "Manufacturer" "Bourns"
			(at 256.54 109.22 0)
			(effects
				(font
					(size 1.27 1.27)
					(thickness 0.15)
				)
				(justify left bottom)
				(hide yes)
			)
		)
		(property "License" "Apache-2.0"
			(at 256.54 111.76 0)
			(effects
				(font
					(size 1.27 1.27)
					(thickness 0.15)
				)
				(justify left bottom)
				(hide yes)
			)
		)
		(property "Author" "Antmicro"
			(at 256.54 114.3 0)
			(effects
				(font
					(size 1.27 1.27)
					(thickness 0.15)
				)
				(justify left bottom)
				(hide yes)
			)
		)
		(property "Val" "49k9"
			(at 243.205 85.09 0)
			(effects
				(font
					(size 1.27 1.27)
					(thickness 0.15)
				)
			)
		)
		(property "Tolerance" "1%"
			(at 256.54 96.52 0)
			(effects
				(font
					(size 1.27 1.27)
				)
				(justify left bottom)
				(hide yes)
			)
		)
		(pin "1"
		)
		(pin "2"
		)
		(instances
			(project ""
				(path ""
					(reference "R34")
					(unit 1)
				)
			)
		)
	)
	(symbol
		(lib_id "antmicropower:+0V9")
		(at 291.465 87.63 0)
		(unit 1)
		(exclude_from_sim no)
		(in_bom yes)
		(on_board yes)
		(dnp no)
		(fields_autoplaced yes)
		(property "Reference" "#PWR0208"
			(at 291.465 91.44 0)
			(effects
				(font
					(size 1.27 1.27)
				)
				(hide yes)
			)
		)
		(property "Value" "+0V9"
			(at 291.465 82.55 0)
			(effects
				(font
					(size 1.27 1.27)
				)
			)
		)
		(property "Footprint" ""
			(at 291.465 87.63 0)
			(effects
				(font
					(size 1.27 1.27)
				)
				(hide yes)
			)
		)
		(property "Datasheet" ""
			(at 291.465 87.63 0)
			(effects
				(font
					(size 1.27 1.27)
				)
				(hide yes)
			)
		)
		(property "Description" ""
			(at 291.465 87.63 0)
			(effects
				(font
					(size 1.27 1.27)
				)
			)
		)
		(pin "1"
		)
		(instances
			(project ""
				(path ""
					(reference "#PWR0208")
					(unit 1)
				)
			)
		)
	)
	(symbol
		(lib_id "antmicropower:+5V")
		(at 243.84 193.04 0)
		(unit 1)
		(exclude_from_sim no)
		(in_bom yes)
		(on_board yes)
		(dnp no)
		(property "Reference" "#PWR0212"
			(at 259.08 195.58 0)
			(effects
				(font
					(size 1.27 1.27)
					(thickness 0.15)
				)
				(justify left bottom)
				(hide yes)
			)
		)
		(property "Value" "+5V"
			(at 243.84 189.23 0)
			(effects
				(font
					(size 1.27 1.27)
					(thickness 0.15)
				)
			)
		)
		(property "Footprint" ""
			(at 259.08 200.66 0)
			(effects
				(font
					(size 1.27 1.27)
					(thickness 0.15)
				)
				(justify left bottom)
				(hide yes)
			)
		)
		(property "Datasheet" ""
			(at 259.08 203.2 0)
			(effects
				(font
					(size 1.27 1.27)
					(thickness 0.15)
				)
				(justify left bottom)
				(hide yes)
			)
		)
		(property "Description" ""
			(at 243.84 193.04 0)
			(effects
				(font
					(size 1.27 1.27)
				)
			)
		)
		(property "Author" "Antmicro"
			(at 259.08 200.66 0)
			(effects
				(font
					(size 1.27 1.27)
					(thickness 0.15)
				)
				(justify left bottom)
				(hide yes)
			)
		)
		(property "License" "Apache-2.0"
			(at 259.08 203.2 0)
			(effects
				(font
					(size 1.27 1.27)
					(thickness 0.15)
				)
				(justify left bottom)
				(hide yes)
			)
		)
		(pin "1"
		)
		(instances
			(project ""
				(path ""
					(reference "#PWR0212")
					(unit 1)
				)
			)
		)
	)
	(symbol
		(lib_id "antmicroResistors0402:R_25k5_0402")
		(at 176.53 184.785 90)
		(unit 1)
		(exclude_from_sim no)
		(in_bom yes)
		(on_board yes)
		(dnp no)
		(property "Reference" "R31"
			(at 177.8 180.975 90)
			(effects
				(font
					(size 1.27 1.27)
					(thickness 0.15)
				)
				(justify right)
			)
		)
		(property "Value" "R_25k5_0402"
			(at 189.23 164.465 0)
			(effects
				(font
					(size 1.27 1.27)
					(thickness 0.15)
				)
				(justify left bottom)
				(hide yes)
			)
		)
		(property "Footprint" "antmicro-footprints:R_0402_1005Metric"
			(at 191.77 164.465 0)
			(effects
				(font
					(size 1.27 1.27)
					(thickness 0.15)
				)
				(justify left bottom)
				(hide yes)
			)
		)
		(property "Datasheet" "https://www.bourns.com/docs/product-datasheets/cr.pdf"
			(at 194.31 164.465 0)
			(effects
				(font
					(size 1.27 1.27)
					(thickness 0.15)
				)
				(justify left bottom)
				(hide yes)
			)
		)
		(property "Description" ""
			(at 176.53 184.785 0)
			(effects
				(font
					(size 1.27 1.27)
				)
			)
		)
		(property "MPN" "CR0402-FX-2552GLF"
			(at 196.85 164.465 0)
			(effects
				(font
					(size 1.27 1.27)
					(thickness 0.15)
				)
				(justify left bottom)
				(hide yes)
			)
		)
		(property "Manufacturer" "Bourns"
			(at 199.39 164.465 0)
			(effects
				(font
					(size 1.27 1.27)
					(thickness 0.15)
				)
				(justify left bottom)
				(hide yes)
			)
		)
		(property "License" "Apache-2.0"
			(at 201.93 164.465 0)
			(effects
				(font
					(size 1.27 1.27)
					(thickness 0.15)
				)
				(justify left bottom)
				(hide yes)
			)
		)
		(property "Author" "Antmicro"
			(at 204.47 164.465 0)
			(effects
				(font
					(size 1.27 1.27)
					(thickness 0.15)
				)
				(justify left bottom)
				(hide yes)
			)
		)
		(property "Val" "25k5"
			(at 177.8 183.515 90)
			(effects
				(font
					(size 1.27 1.27)
					(thickness 0.15)
				)
				(justify right)
			)
		)
		(property "Tolerance" "1%"
			(at 186.69 164.465 0)
			(effects
				(font
					(size 1.27 1.27)
				)
				(justify left bottom)
				(hide yes)
			)
		)
		(pin "1"
		)
		(pin "2"
		)
		(instances
			(project ""
				(path ""
					(reference "R31")
					(unit 1)
				)
			)
		)
	)
	(symbol
		(lib_id "antmicropower:GND")
		(at 247.015 120.015 0)
		(unit 1)
		(exclude_from_sim no)
		(in_bom yes)
		(on_board yes)
		(dnp no)
		(property "Reference" "#PWR0215"
			(at 247.015 126.365 0)
			(effects
				(font
					(size 1.27 1.27)
				)
				(hide yes)
			)
		)
		(property "Value" "GND"
			(at 245.11 123.825 0)
			(effects
				(font
					(size 1.27 1.27)
				)
				(justify left)
			)
		)
		(property "Footprint" ""
			(at 255.905 127.635 0)
			(effects
				(font
					(size 1.27 1.27)
					(thickness 0.15)
				)
				(justify left bottom)
				(hide yes)
			)
		)
		(property "Datasheet" ""
			(at 255.905 132.715 0)
			(effects
				(font
					(size 1.27 1.27)
					(thickness 0.15)
				)
				(justify left bottom)
				(hide yes)
			)
		)
		(property "Description" ""
			(at 247.015 120.015 0)
			(effects
				(font
					(size 1.27 1.27)
				)
			)
		)
		(property "Author" "Antmicro"
			(at 255.905 127.635 0)
			(effects
				(font
					(size 1.27 1.27)
					(thickness 0.15)
				)
				(justify left bottom)
				(hide yes)
			)
		)
		(property "License" "Apache-2.0"
			(at 255.905 130.175 0)
			(effects
				(font
					(size 1.27 1.27)
					(thickness 0.15)
				)
				(justify left bottom)
				(hide yes)
			)
		)
		(pin "1"
		)
		(instances
			(project ""
				(path ""
					(reference "#PWR0215")
					(unit 1)
				)
			)
		)
	)
	(symbol
		(lib_id "antmicroResistors0603:R_0R_22.4A_0603")
		(at 285.115 88.9 0)
		(mirror y)
		(unit 1)
		(exclude_from_sim no)
		(in_bom yes)
		(on_board yes)
		(dnp no)
		(property "Reference" "R44"
			(at 285.115 87.63 0)
			(effects
				(font
					(size 1.27 1.27)
					(thickness 0.15)
				)
				(justify right)
			)
		)
		(property "Value" "R_0R_22.4A_0603"
			(at 282.575 80.01 0)
			(effects
				(font
					(size 1.27 1.27)
					(thickness 0.15)
				)
				(hide yes)
			)
		)
		(property "Footprint" "antmicro-footprints:R_0603_1608Metric"
			(at 269.875 99.06 0)
			(effects
				(font
					(size 1.27 1.27)
					(thickness 0.15)
				)
				(justify left bottom)
				(hide yes)
			)
		)
		(property "Datasheet" "https://fscdn.rohm.com/en/products/databook/datasheet/passive/resistor/chip_resistor/pmr-jpw-e.pdf"
			(at 269.875 101.6 0)
			(effects
				(font
					(size 1.27 1.27)
					(thickness 0.15)
				)
				(justify left bottom)
				(hide yes)
			)
		)
		(property "Description" ""
			(at 285.115 88.9 0)
			(effects
				(font
					(size 1.27 1.27)
				)
			)
		)
		(property "MPN" "PMR03EZPJ000"
			(at 269.875 104.14 0)
			(effects
				(font
					(size 1.27 1.27)
					(thickness 0.15)
				)
				(justify left bottom)
				(hide yes)
			)
		)
		(property "Manufacturer" "ROHM Semiconductor"
			(at 269.875 106.68 0)
			(effects
				(font
					(size 1.27 1.27)
					(thickness 0.15)
				)
				(justify left bottom)
				(hide yes)
			)
		)
		(property "Val" "0R"
			(at 278.765 87.63 0)
			(effects
				(font
					(size 1.27 1.27)
					(thickness 0.15)
				)
			)
		)
		(property "Max. Curr." "22.4A"
			(at 282.575 91.44 0)
			(effects
				(font
					(size 1.27 1.27)
					(thickness 0.15)
				)
			)
		)
		(property "Author" "Antmicro"
			(at 269.875 111.76 0)
			(effects
				(font
					(size 1.27 1.27)
					(thickness 0.15)
				)
				(justify left bottom)
				(hide yes)
			)
		)
		(property "License" "Apache-2.0"
			(at 269.875 114.3 0)
			(effects
				(font
					(size 1.27 1.27)
					(thickness 0.15)
				)
				(justify left bottom)
				(hide yes)
			)
		)
		(property "Tolerance" "template_tolerance"
			(at 264.795 99.06 0)
			(effects
				(font
					(size 1.27 1.27)
				)
				(justify left bottom)
				(hide yes)
			)
		)
		(pin "1"
		)
		(pin "2"
		)
		(instances
			(project ""
				(path ""
					(reference "R44")
					(unit 1)
				)
			)
		)
	)
	(symbol
		(lib_id "antmicropower:GND")
		(at 243.84 218.44 0)
		(unit 1)
		(exclude_from_sim no)
		(in_bom yes)
		(on_board yes)
		(dnp no)
		(fields_autoplaced yes)
		(property "Reference" "#PWR0210"
			(at 252.73 220.98 0)
			(effects
				(font
					(size 1.27 1.27)
					(thickness 0.15)
				)
				(justify left bottom)
				(hide yes)
			)
		)
		(property "Value" "GND"
			(at 243.84 222.885 0)
			(effects
				(font
					(size 1.27 1.27)
					(thickness 0.15)
				)
			)
		)
		(property "Footprint" ""
			(at 252.73 226.06 0)
			(effects
				(font
					(size 1.27 1.27)
					(thickness 0.15)
				)
				(justify left bottom)
				(hide yes)
			)
		)
		(property "Datasheet" ""
			(at 252.73 231.14 0)
			(effects
				(font
					(size 1.27 1.27)
					(thickness 0.15)
				)
				(justify left bottom)
				(hide yes)
			)
		)
		(property "Description" ""
			(at 243.84 218.44 0)
			(effects
				(font
					(size 1.27 1.27)
				)
			)
		)
		(property "Author" "Antmicro"
			(at 252.73 226.06 0)
			(effects
				(font
					(size 1.27 1.27)
					(thickness 0.15)
				)
				(justify left bottom)
				(hide yes)
			)
		)
		(property "License" "Apache-2.0"
			(at 252.73 228.6 0)
			(effects
				(font
					(size 1.27 1.27)
					(thickness 0.15)
				)
				(justify left bottom)
				(hide yes)
			)
		)
		(pin "1"
		)
		(instances
			(project ""
				(path ""
					(reference "#PWR0210")
					(unit 1)
				)
			)
		)
	)
	(symbol
		(lib_id "antmicroCapacitors0402:C_4u7_0402")
		(at 302.26 186.055 90)
		(unit 1)
		(exclude_from_sim no)
		(in_bom yes)
		(on_board yes)
		(dnp no)
		(property "Reference" "C21"
			(at 302.895 181.61 90)
			(effects
				(font
					(size 1.27 1.27)
					(thickness 0.15)
				)
				(justify right)
			)
		)
		(property "Value" "C_4u7_0402"
			(at 312.42 165.735 0)
			(effects
				(font
					(size 1.27 1.27)
					(thickness 0.15)
				)
				(justify left bottom)
				(hide yes)
			)
		)
		(property "Footprint" "antmicro-footprints:C_0402_1005Metric"
			(at 314.96 165.735 0)
			(effects
				(font
					(size 1.27 1.27)
					(thickness 0.15)
				)
				(justify left bottom)
				(hide yes)
			)
		)
		(property "Datasheet" "https://www.murata.com/products/productdetail?partno=GRM155R61A475MEAA%23"
			(at 317.5 165.735 0)
			(effects
				(font
					(size 1.27 1.27)
					(thickness 0.15)
				)
				(justify left bottom)
				(hide yes)
			)
		)
		(property "Description" ""
			(at 302.26 186.055 0)
			(effects
				(font
					(size 1.27 1.27)
				)
			)
		)
		(property "MPN" "GRM155R61A475MEAAD"
			(at 320.04 165.735 0)
			(effects
				(font
					(size 1.27 1.27)
					(thickness 0.15)
				)
				(justify left bottom)
				(hide yes)
			)
		)
		(property "Manufacturer" "Murata"
			(at 322.58 165.735 0)
			(effects
				(font
					(size 1.27 1.27)
					(thickness 0.15)
				)
				(justify left bottom)
				(hide yes)
			)
		)
		(property "License" "Apache-2.0"
			(at 325.12 165.735 0)
			(effects
				(font
					(size 1.27 1.27)
					(thickness 0.15)
				)
				(justify left bottom)
				(hide yes)
			)
		)
		(property "Author" "Antmicro"
			(at 327.66 165.735 0)
			(effects
				(font
					(size 1.27 1.27)
					(thickness 0.15)
				)
				(justify left bottom)
				(hide yes)
			)
		)
		(property "Val" "4u7"
			(at 302.895 185.42 90)
			(effects
				(font
					(size 1.27 1.27)
					(thickness 0.15)
				)
				(justify right)
			)
		)
		(property "Voltage" ""
			(at 330.2 165.735 0)
			(effects
				(font
					(size 1.27 1.27)
				)
				(justify left bottom)
				(hide yes)
			)
		)
		(property "Dielectric" ""
			(at 332.74 165.735 0)
			(effects
				(font
					(size 1.27 1.27)
				)
				(justify left bottom)
				(hide yes)
			)
		)
		(pin "1"
		)
		(pin "2"
		)
		(instances
			(project ""
				(path ""
					(reference "C21")
					(unit 1)
				)
			)
		)
	)
	(symbol
		(lib_id "antmicropower:+1V8")
		(at 291.465 72.39 0)
		(unit 1)
		(exclude_from_sim no)
		(in_bom yes)
		(on_board yes)
		(dnp no)
		(fields_autoplaced yes)
		(property "Reference" "#PWR0209"
			(at 306.705 74.93 0)
			(effects
				(font
					(size 1.27 1.27)
					(thickness 0.15)
				)
				(justify left bottom)
				(hide yes)
			)
		)
		(property "Value" "+1V8"
			(at 291.465 67.31 0)
			(effects
				(font
					(size 1.27 1.27)
					(thickness 0.15)
				)
			)
		)
		(property "Footprint" ""
			(at 306.705 80.01 0)
			(effects
				(font
					(size 1.27 1.27)
					(thickness 0.15)
				)
				(justify left bottom)
				(hide yes)
			)
		)
		(property "Datasheet" ""
			(at 306.705 82.55 0)
			(effects
				(font
					(size 1.27 1.27)
					(thickness 0.15)
				)
				(justify left bottom)
				(hide yes)
			)
		)
		(property "Description" ""
			(at 291.465 72.39 0)
			(effects
				(font
					(size 1.27 1.27)
				)
			)
		)
		(property "Author" "Antmicro"
			(at 306.705 80.01 0)
			(effects
				(font
					(size 1.27 1.27)
					(thickness 0.15)
				)
				(justify left bottom)
				(hide yes)
			)
		)
		(property "License" "Apache-2.0"
			(at 306.705 82.55 0)
			(effects
				(font
					(size 1.27 1.27)
					(thickness 0.15)
				)
				(justify left bottom)
				(hide yes)
			)
		)
		(pin "1"
		)
		(instances
			(project ""
				(path ""
					(reference "#PWR0209")
					(unit 1)
				)
			)
		)
	)
	(symbol
		(lib_id "antmicroLEDIndicationDiscrete:LED_G_0603_KP-1608CGCK")
		(at 243.84 198.755 270)
		(unit 1)
		(exclude_from_sim no)
		(in_bom yes)
		(on_board yes)
		(dnp no)
		(fields_autoplaced yes)
		(property "Reference" "D2"
			(at 247.65 201.2949 90)
			(effects
				(font
					(size 1.27 1.27)
					(thickness 0.15)
				)
				(justify left)
			)
		)
		(property "Value" "LED_G_0603_KP-1608CGCK"
			(at 247.65 203.8349 90)
			(effects
				(font
					(size 1.27 1.27)
					(thickness 0.15)
				)
				(justify left)
				(hide yes)
			)
		)
		(property "Footprint" "antmicro-footprints:LED_0603_1608Metric_G"
			(at 233.68 221.615 0)
			(effects
				(font
					(size 1.27 1.27)
					(thickness 0.15)
				)
				(justify left bottom)
				(hide yes)
			)
		)
		(property "Datasheet" "http://www.farnell.com/datasheets/2045956.pdf"
			(at 231.14 221.615 0)
			(effects
				(font
					(size 1.27 1.27)
					(thickness 0.15)
				)
				(justify left bottom)
				(hide yes)
			)
		)
		(property "Description" ""
			(at 243.84 198.755 0)
			(effects
				(font
					(size 1.27 1.27)
				)
			)
		)
		(property "MPN" "KP-1608CGCK"
			(at 228.6 221.615 0)
			(effects
				(font
					(size 1.27 1.27)
					(thickness 0.15)
				)
				(justify left bottom)
				(hide yes)
			)
		)
		(property "Manufacturer" "Kingbright"
			(at 226.06 221.615 0)
			(effects
				(font
					(size 1.27 1.27)
					(thickness 0.15)
				)
				(justify left bottom)
				(hide yes)
			)
		)
		(property "Author" "Antmicro"
			(at 223.52 221.615 0)
			(effects
				(font
					(size 1.27 1.27)
					(thickness 0.15)
				)
				(justify left bottom)
				(hide yes)
			)
		)
		(property "License" "Apache-2.0"
			(at 220.98 221.615 0)
			(effects
				(font
					(size 1.27 1.27)
					(thickness 0.15)
				)
				(justify left bottom)
				(hide yes)
			)
		)
		(pin "1"
		)
		(pin "2"
		)
		(instances
			(project ""
				(path ""
					(reference "D2")
					(unit 1)
				)
			)
		)
	)
	(symbol
		(lib_id "antmicropower:GND")
		(at 257.81 80.645 0)
		(unit 1)
		(exclude_from_sim no)
		(in_bom yes)
		(on_board yes)
		(dnp no)
		(fields_autoplaced yes)
		(property "Reference" "#PWR0223"
			(at 266.7 83.185 0)
			(effects
				(font
					(size 1.27 1.27)
					(thickness 0.15)
				)
				(justify left bottom)
				(hide yes)
			)
		)
		(property "Value" "GND"
			(at 257.81 85.09 0)
			(effects
				(font
					(size 1.27 1.27)
					(thickness 0.15)
				)
			)
		)
		(property "Footprint" ""
			(at 266.7 88.265 0)
			(effects
				(font
					(size 1.27 1.27)
					(thickness 0.15)
				)
				(justify left bottom)
				(hide yes)
			)
		)
		(property "Datasheet" ""
			(at 266.7 93.345 0)
			(effects
				(font
					(size 1.27 1.27)
					(thickness 0.15)
				)
				(justify left bottom)
				(hide yes)
			)
		)
		(property "Description" ""
			(at 257.81 80.645 0)
			(effects
				(font
					(size 1.27 1.27)
				)
			)
		)
		(property "Author" "Antmicro"
			(at 266.7 88.265 0)
			(effects
				(font
					(size 1.27 1.27)
					(thickness 0.15)
				)
				(justify left bottom)
				(hide yes)
			)
		)
		(property "License" "Apache-2.0"
			(at 266.7 90.805 0)
			(effects
				(font
					(size 1.27 1.27)
					(thickness 0.15)
				)
				(justify left bottom)
				(hide yes)
			)
		)
		(pin "1"
		)
		(instances
			(project ""
				(path ""
					(reference "#PWR0223")
					(unit 1)
				)
			)
		)
	)
	(symbol
		(lib_id "antmicroResistors0402:R_100k_0402")
		(at 236.22 96.52 0)
		(unit 1)
		(exclude_from_sim no)
		(in_bom yes)
		(on_board yes)
		(dnp no)
		(property "Reference" "R35"
			(at 234.315 95.25 0)
			(effects
				(font
					(size 1.27 1.27)
					(thickness 0.15)
				)
			)
		)
		(property "Value" "R_100k_0402"
			(at 256.54 109.22 0)
			(effects
				(font
					(size 1.27 1.27)
					(thickness 0.15)
				)
				(justify left bottom)
				(hide yes)
			)
		)
		(property "Footprint" "antmicro-footprints:R_0402_1005Metric"
			(at 256.54 111.76 0)
			(effects
				(font
					(size 1.27 1.27)
					(thickness 0.15)
				)
				(justify left bottom)
				(hide yes)
			)
		)
		(property "Datasheet" "https://www.bourns.com/docs/product-datasheets/cr.pdf"
			(at 256.54 114.3 0)
			(effects
				(font
					(size 1.27 1.27)
					(thickness 0.15)
				)
				(justify left bottom)
				(hide yes)
			)
		)
		(property "Description" ""
			(at 236.22 96.52 0)
			(effects
				(font
					(size 1.27 1.27)
				)
			)
		)
		(property "MPN" "CR0402-FX-1003GLF"
			(at 256.54 116.84 0)
			(effects
				(font
					(size 1.27 1.27)
					(thickness 0.15)
				)
				(justify left bottom)
				(hide yes)
			)
		)
		(property "Manufacturer" "Bourns"
			(at 256.54 119.38 0)
			(effects
				(font
					(size 1.27 1.27)
					(thickness 0.15)
				)
				(justify left bottom)
				(hide yes)
			)
		)
		(property "License" "Apache-2.0"
			(at 256.54 121.92 0)
			(effects
				(font
					(size 1.27 1.27)
					(thickness 0.15)
				)
				(justify left bottom)
				(hide yes)
			)
		)
		(property "Author" "Antmicro"
			(at 256.54 124.46 0)
			(effects
				(font
					(size 1.27 1.27)
					(thickness 0.15)
				)
				(justify left bottom)
				(hide yes)
			)
		)
		(property "Val" "100k"
			(at 243.205 95.25 0)
			(effects
				(font
					(size 1.27 1.27)
					(thickness 0.15)
				)
			)
		)
		(property "Tolerance" "1%"
			(at 256.54 106.68 0)
			(effects
				(font
					(size 1.27 1.27)
				)
				(justify left bottom)
				(hide yes)
			)
		)
		(pin "1"
		)
		(pin "2"
		)
		(instances
			(project ""
				(path ""
					(reference "R35")
					(unit 1)
				)
			)
		)
	)
	(symbol
		(lib_id "antmicroResistors0402:R_0R_0402")
		(at 276.225 192.405 90)
		(unit 1)
		(exclude_from_sim no)
		(in_bom no)
		(on_board yes)
		(dnp yes)
		(property "Reference" "R47"
			(at 274.32 188.595 90)
			(effects
				(font
					(size 1.27 1.27)
					(thickness 0.15)
				)
				(justify left)
			)
		)
		(property "Value" "R_0R_0402"
			(at 288.925 172.085 0)
			(effects
				(font
					(size 1.27 1.27)
					(thickness 0.15)
				)
				(justify left bottom)
				(hide yes)
			)
		)
		(property "Footprint" "antmicro-footprints:R_0402_1005Metric"
			(at 291.465 172.085 0)
			(effects
				(font
					(size 1.27 1.27)
					(thickness 0.15)
				)
				(justify left bottom)
				(hide yes)
			)
		)
		(property "Datasheet" "https://industrial.panasonic.com/cdbs/www-data/pdf/RDA0000/AOA0000C301.pdf"
			(at 294.005 172.085 0)
			(effects
				(font
					(size 1.27 1.27)
					(thickness 0.15)
				)
				(justify left bottom)
				(hide yes)
			)
		)
		(property "Description" ""
			(at 276.225 192.405 0)
			(effects
				(font
					(size 1.27 1.27)
				)
			)
		)
		(property "MPN" "ERJ2GE0R00X"
			(at 296.545 172.085 0)
			(effects
				(font
					(size 1.27 1.27)
					(thickness 0.15)
				)
				(justify left bottom)
				(hide yes)
			)
		)
		(property "Manufacturer" "Panasonic"
			(at 299.085 172.085 0)
			(effects
				(font
					(size 1.27 1.27)
					(thickness 0.15)
				)
				(justify left bottom)
				(hide yes)
			)
		)
		(property "License" "Apache-2.0"
			(at 301.625 172.085 0)
			(effects
				(font
					(size 1.27 1.27)
					(thickness 0.15)
				)
				(justify left bottom)
				(hide yes)
			)
		)
		(property "Author" "Antmicro"
			(at 304.165 172.085 0)
			(effects
				(font
					(size 1.27 1.27)
					(thickness 0.15)
				)
				(justify left bottom)
				(hide yes)
			)
		)
		(property "Val" "0R"
			(at 274.32 191.135 90)
			(effects
				(font
					(size 1.27 1.27)
					(thickness 0.15)
				)
				(justify left)
			)
		)
		(property "Tolerance" "~"
			(at 286.385 172.085 0)
			(effects
				(font
					(size 1.27 1.27)
				)
				(justify left bottom)
				(hide yes)
			)
		)
		(property "Current" "1A"
			(at 306.705 172.085 0)
			(effects
				(font
					(size 1.27 1.27)
					(thickness 0.15)
				)
				(justify left bottom)
				(hide yes)
			)
		)
		(pin "1"
		)
		(pin "2"
		)
		(instances
			(project ""
				(path ""
					(reference "R47")
					(unit 1)
				)
			)
		)
	)
	(symbol
		(lib_id "antmicroCapacitors0402:C_4u7_0402")
		(at 162.56 184.785 90)
		(unit 1)
		(exclude_from_sim no)
		(in_bom yes)
		(on_board yes)
		(dnp no)
		(property "Reference" "C8"
			(at 163.195 180.34 90)
			(effects
				(font
					(size 1.27 1.27)
					(thickness 0.15)
				)
				(justify right)
			)
		)
		(property "Value" "C_4u7_0402"
			(at 172.72 164.465 0)
			(effects
				(font
					(size 1.27 1.27)
					(thickness 0.15)
				)
				(justify left bottom)
				(hide yes)
			)
		)
		(property "Footprint" "antmicro-footprints:C_0402_1005Metric"
			(at 175.26 164.465 0)
			(effects
				(font
					(size 1.27 1.27)
					(thickness 0.15)
				)
				(justify left bottom)
				(hide yes)
			)
		)
		(property "Datasheet" "https://www.murata.com/products/productdetail?partno=GRM155R61A475MEAA%23"
			(at 177.8 164.465 0)
			(effects
				(font
					(size 1.27 1.27)
					(thickness 0.15)
				)
				(justify left bottom)
				(hide yes)
			)
		)
		(property "Description" ""
			(at 162.56 184.785 0)
			(effects
				(font
					(size 1.27 1.27)
				)
			)
		)
		(property "MPN" "GRM155R61A475MEAAD"
			(at 180.34 164.465 0)
			(effects
				(font
					(size 1.27 1.27)
					(thickness 0.15)
				)
				(justify left bottom)
				(hide yes)
			)
		)
		(property "Manufacturer" "Murata"
			(at 182.88 164.465 0)
			(effects
				(font
					(size 1.27 1.27)
					(thickness 0.15)
				)
				(justify left bottom)
				(hide yes)
			)
		)
		(property "License" "Apache-2.0"
			(at 185.42 164.465 0)
			(effects
				(font
					(size 1.27 1.27)
					(thickness 0.15)
				)
				(justify left bottom)
				(hide yes)
			)
		)
		(property "Author" "Antmicro"
			(at 187.96 164.465 0)
			(effects
				(font
					(size 1.27 1.27)
					(thickness 0.15)
				)
				(justify left bottom)
				(hide yes)
			)
		)
		(property "Val" "4u7"
			(at 163.195 184.15 90)
			(effects
				(font
					(size 1.27 1.27)
					(thickness 0.15)
				)
				(justify right)
			)
		)
		(property "Voltage" ""
			(at 190.5 164.465 0)
			(effects
				(font
					(size 1.27 1.27)
				)
				(justify left bottom)
				(hide yes)
			)
		)
		(property "Dielectric" ""
			(at 193.04 164.465 0)
			(effects
				(font
					(size 1.27 1.27)
				)
				(justify left bottom)
				(hide yes)
			)
		)
		(pin "1"
		)
		(pin "2"
		)
		(instances
			(project ""
				(path ""
					(reference "C8")
					(unit 1)
				)
			)
		)
	)
	(symbol
		(lib_id "antmicropower:GND")
		(at 266.7 80.645 0)
		(unit 1)
		(exclude_from_sim no)
		(in_bom yes)
		(on_board yes)
		(dnp no)
		(fields_autoplaced yes)
		(property "Reference" "#PWR0207"
			(at 275.59 83.185 0)
			(effects
				(font
					(size 1.27 1.27)
					(thickness 0.15)
				)
				(justify left bottom)
				(hide yes)
			)
		)
		(property "Value" "GND"
			(at 266.7 85.09 0)
			(effects
				(font
					(size 1.27 1.27)
					(thickness 0.15)
				)
			)
		)
		(property "Footprint" ""
			(at 275.59 88.265 0)
			(effects
				(font
					(size 1.27 1.27)
					(thickness 0.15)
				)
				(justify left bottom)
				(hide yes)
			)
		)
		(property "Datasheet" ""
			(at 275.59 93.345 0)
			(effects
				(font
					(size 1.27 1.27)
					(thickness 0.15)
				)
				(justify left bottom)
				(hide yes)
			)
		)
		(property "Description" ""
			(at 266.7 80.645 0)
			(effects
				(font
					(size 1.27 1.27)
				)
			)
		)
		(property "Author" "Antmicro"
			(at 275.59 88.265 0)
			(effects
				(font
					(size 1.27 1.27)
					(thickness 0.15)
				)
				(justify left bottom)
				(hide yes)
			)
		)
		(property "License" "Apache-2.0"
			(at 275.59 90.805 0)
			(effects
				(font
					(size 1.27 1.27)
					(thickness 0.15)
				)
				(justify left bottom)
				(hide yes)
			)
		)
		(pin "1"
		)
		(instances
			(project ""
				(path ""
					(reference "#PWR0207")
					(unit 1)
				)
			)
		)
	)
	(symbol
		(lib_id "antmicropower:PWR_FLAG")
		(at 345.44 178.435 270)
		(unit 1)
		(exclude_from_sim no)
		(in_bom yes)
		(on_board yes)
		(dnp no)
		(property "Reference" "#FLG0103"
			(at 347.345 178.435 0)
			(effects
				(font
					(size 1.27 1.27)
				)
				(hide yes)
			)
		)
		(property "Value" "PWR_FLAG"
			(at 348.615 178.435 90)
			(effects
				(font
					(size 1.27 1.27)
				)
				(justify left)
			)
		)
		(property "Footprint" ""
			(at 345.44 178.435 0)
			(effects
				(font
					(size 1.27 1.27)
				)
				(hide yes)
			)
		)
		(property "Datasheet" ""
			(at 345.44 178.435 0)
			(effects
				(font
					(size 1.27 1.27)
				)
				(hide yes)
			)
		)
		(property "Description" ""
			(at 345.44 178.435 0)
			(effects
				(font
					(size 1.27 1.27)
				)
			)
		)
		(pin "1"
		)
		(instances
			(project ""
				(path ""
					(reference "#FLG0103")
					(unit 1)
				)
			)
		)
	)
	(symbol
		(lib_id "antmicropower:PWR_FLAG")
		(at 294.64 104.14 270)
		(unit 1)
		(exclude_from_sim no)
		(in_bom yes)
		(on_board yes)
		(dnp no)
		(property "Reference" "#FLG0101"
			(at 296.545 104.14 0)
			(effects
				(font
					(size 1.27 1.27)
				)
				(hide yes)
			)
		)
		(property "Value" "PWR_FLAG"
			(at 297.815 104.14 90)
			(effects
				(font
					(size 1.27 1.27)
				)
				(justify left)
			)
		)
		(property "Footprint" ""
			(at 294.64 104.14 0)
			(effects
				(font
					(size 1.27 1.27)
				)
				(hide yes)
			)
		)
		(property "Datasheet" ""
			(at 294.64 104.14 0)
			(effects
				(font
					(size 1.27 1.27)
				)
				(hide yes)
			)
		)
		(property "Description" ""
			(at 294.64 104.14 0)
			(effects
				(font
					(size 1.27 1.27)
				)
			)
		)
		(pin "1"
		)
		(instances
			(project ""
				(path ""
					(reference "#FLG0101")
					(unit 1)
				)
			)
		)
	)
	(symbol
		(lib_id "antmicroResistors0402:R_3k9_0402")
		(at 281.305 184.785 90)
		(unit 1)
		(exclude_from_sim no)
		(in_bom yes)
		(on_board yes)
		(dnp no)
		(fields_autoplaced yes)
		(property "Reference" "R51"
			(at 283.845 180.9749 90)
			(effects
				(font
					(size 1.27 1.27)
					(thickness 0.15)
				)
				(justify right)
			)
		)
		(property "Value" "R_3k9_0402"
			(at 294.005 164.465 0)
			(effects
				(font
					(size 1.27 1.27)
					(thickness 0.15)
				)
				(justify left bottom)
				(hide yes)
			)
		)
		(property "Footprint" "antmicro-footprints:R_0402_1005Metric"
			(at 296.545 164.465 0)
			(effects
				(font
					(size 1.27 1.27)
					(thickness 0.15)
				)
				(justify left bottom)
				(hide yes)
			)
		)
		(property "Datasheet" "https://www.bourns.com/docs/product-datasheets/cr.pdf"
			(at 299.085 164.465 0)
			(effects
				(font
					(size 1.27 1.27)
					(thickness 0.15)
				)
				(justify left bottom)
				(hide yes)
			)
		)
		(property "Description" ""
			(at 281.305 184.785 0)
			(effects
				(font
					(size 1.27 1.27)
				)
			)
		)
		(property "MPN" "CR0402-FX-3901GLF"
			(at 301.625 164.465 0)
			(effects
				(font
					(size 1.27 1.27)
					(thickness 0.15)
				)
				(justify left bottom)
				(hide yes)
			)
		)
		(property "Manufacturer" "Bourns"
			(at 304.165 164.465 0)
			(effects
				(font
					(size 1.27 1.27)
					(thickness 0.15)
				)
				(justify left bottom)
				(hide yes)
			)
		)
		(property "License" "Apache-2.0"
			(at 306.705 164.465 0)
			(effects
				(font
					(size 1.27 1.27)
					(thickness 0.15)
				)
				(justify left bottom)
				(hide yes)
			)
		)
		(property "Author" "Antmicro"
			(at 309.245 164.465 0)
			(effects
				(font
					(size 1.27 1.27)
					(thickness 0.15)
				)
				(justify left bottom)
				(hide yes)
			)
		)
		(property "Val" "3k9"
			(at 283.845 183.5149 90)
			(effects
				(font
					(size 1.27 1.27)
					(thickness 0.15)
				)
				(justify right)
			)
		)
		(property "Tolerance" "1%"
			(at 291.465 164.465 0)
			(effects
				(font
					(size 1.27 1.27)
				)
				(justify left bottom)
				(hide yes)
			)
		)
		(pin "1"
		)
		(pin "2"
		)
		(instances
			(project ""
				(path ""
					(reference "R51")
					(unit 1)
				)
			)
		)
	)
	(symbol
		(lib_id "antmicroCapacitors0603:C_22u_0603")
		(at 257.81 95.25 90)
		(unit 1)
		(exclude_from_sim no)
		(in_bom yes)
		(on_board yes)
		(dnp no)
		(property "Reference" "C15"
			(at 258.445 90.805 90)
			(effects
				(font
					(size 1.27 1.27)
					(thickness 0.15)
				)
				(justify right)
			)
		)
		(property "Value" "C_22u_0603"
			(at 267.97 74.93 0)
			(effects
				(font
					(size 1.27 1.27)
					(thickness 0.15)
				)
				(justify left bottom)
				(hide yes)
			)
		)
		(property "Footprint" "antmicro-footprints:C_0603_1608Metric"
			(at 270.51 74.93 0)
			(effects
				(font
					(size 1.27 1.27)
					(thickness 0.15)
				)
				(justify left bottom)
				(hide yes)
			)
		)
		(property "Datasheet" "https://www.murata.com/products/productdetail?partno=GRM188R60J226MEA0%23"
			(at 273.05 74.93 0)
			(effects
				(font
					(size 1.27 1.27)
					(thickness 0.15)
				)
				(justify left bottom)
				(hide yes)
			)
		)
		(property "Description" ""
			(at 257.81 95.25 0)
			(effects
				(font
					(size 1.27 1.27)
				)
			)
		)
		(property "MPN" "GRM188R60J226MEA0D"
			(at 275.59 74.93 0)
			(effects
				(font
					(size 1.27 1.27)
					(thickness 0.15)
				)
				(justify left bottom)
				(hide yes)
			)
		)
		(property "Manufacturer" "Murata"
			(at 278.13 74.93 0)
			(effects
				(font
					(size 1.27 1.27)
					(thickness 0.15)
				)
				(justify left bottom)
				(hide yes)
			)
		)
		(property "License" "Apache-2.0"
			(at 280.67 74.93 0)
			(effects
				(font
					(size 1.27 1.27)
					(thickness 0.15)
				)
				(justify left bottom)
				(hide yes)
			)
		)
		(property "Author" "Antmicro"
			(at 283.21 74.93 0)
			(effects
				(font
					(size 1.27 1.27)
					(thickness 0.15)
				)
				(justify left bottom)
				(hide yes)
			)
		)
		(property "Val" "22u"
			(at 258.445 94.615 90)
			(effects
				(font
					(size 1.27 1.27)
					(thickness 0.15)
				)
				(justify right)
			)
		)
		(property "Voltage" ""
			(at 285.75 74.93 0)
			(effects
				(font
					(size 1.27 1.27)
				)
				(justify left bottom)
				(hide yes)
			)
		)
		(property "Dielectric" ""
			(at 288.29 74.93 0)
			(effects
				(font
					(size 1.27 1.27)
				)
				(justify left bottom)
				(hide yes)
			)
		)
		(pin "1"
		)
		(pin "2"
		)
		(instances
			(project ""
				(path ""
					(reference "C15")
					(unit 1)
				)
			)
		)
	)
	(symbol
		(lib_id "antmicroCapacitorsmisc:C_22u_25V_0805")
		(at 180.975 64.135 90)
		(unit 1)
		(exclude_from_sim no)
		(in_bom yes)
		(on_board yes)
		(dnp no)
		(property "Reference" "C11"
			(at 181.61 59.69 90)
			(effects
				(font
					(size 1.27 1.27)
					(thickness 0.15)
				)
				(justify right)
			)
		)
		(property "Value" "C_22u_25V_0805"
			(at 191.135 43.815 0)
			(effects
				(font
					(size 1.27 1.27)
					(thickness 0.15)
				)
				(justify left bottom)
				(hide yes)
			)
		)
		(property "Footprint" "antmicro-footprints:C_0805_2012Metric"
			(at 193.675 43.815 0)
			(effects
				(font
					(size 1.27 1.27)
					(thickness 0.15)
				)
				(justify left bottom)
				(hide yes)
			)
		)
		(property "Datasheet" "https://product.samsungsem.com/mlcc/CL21A226MAYNNN.do"
			(at 196.215 43.815 0)
			(effects
				(font
					(size 1.27 1.27)
					(thickness 0.15)
				)
				(justify left bottom)
				(hide yes)
			)
		)
		(property "Description" ""
			(at 180.975 64.135 0)
			(effects
				(font
					(size 1.27 1.27)
				)
			)
		)
		(property "MPN" "CL21A226MAYNNNE"
			(at 198.755 43.815 0)
			(effects
				(font
					(size 1.27 1.27)
					(thickness 0.15)
				)
				(justify left bottom)
				(hide yes)
			)
		)
		(property "Manufacturer" "Samsung Electro-Mechanics"
			(at 201.295 43.815 0)
			(effects
				(font
					(size 1.27 1.27)
					(thickness 0.15)
				)
				(justify left bottom)
				(hide yes)
			)
		)
		(property "License" "Apache-2.0"
			(at 203.835 43.815 0)
			(effects
				(font
					(size 1.27 1.27)
					(thickness 0.15)
				)
				(justify left bottom)
				(hide yes)
			)
		)
		(property "Author" "Antmicro"
			(at 206.375 43.815 0)
			(effects
				(font
					(size 1.27 1.27)
					(thickness 0.15)
				)
				(justify left bottom)
				(hide yes)
			)
		)
		(property "Val" "22u_25V"
			(at 181.61 63.5 90)
			(effects
				(font
					(size 1.27 1.27)
					(thickness 0.15)
				)
				(justify right)
			)
		)
		(property "Voltage" ""
			(at 208.915 43.815 0)
			(effects
				(font
					(size 1.27 1.27)
				)
				(justify left bottom)
				(hide yes)
			)
		)
		(property "Dielectric" ""
			(at 211.455 43.815 0)
			(effects
				(font
					(size 1.27 1.27)
				)
				(justify left bottom)
				(hide yes)
			)
		)
		(pin "1"
		)
		(pin "2"
		)
		(instances
			(project ""
				(path ""
					(reference "C11")
					(unit 1)
				)
			)
		)
	)
	(symbol
		(lib_id "antmicroTestPoints:TP_1mm_SMD")
		(at 191.135 93.345 0)
		(mirror y)
		(unit 1)
		(exclude_from_sim no)
		(in_bom yes)
		(on_board yes)
		(dnp no)
		(property "Reference" "TP2"
			(at 186.69 93.345 0)
			(effects
				(font
					(size 1.27 1.27)
					(thickness 0.15)
				)
				(justify left)
			)
		)
		(property "Value" "TP_1mm_SMD"
			(at 175.895 100.965 0)
			(effects
				(font
					(size 1.27 1.27)
					(thickness 0.15)
				)
				(justify left bottom)
				(hide yes)
			)
		)
		(property "Footprint" "antmicro-footprints:TP_SMD_1mm"
			(at 175.895 103.505 0)
			(effects
				(font
					(size 1.27 1.27)
					(thickness 0.15)
				)
				(justify left bottom)
				(hide yes)
			)
		)
		(property "Datasheet" ""
			(at 173.355 106.045 0)
			(effects
				(font
					(size 1.27 1.27)
					(thickness 0.15)
				)
				(justify left bottom)
				(hide yes)
			)
		)
		(property "Description" ""
			(at 191.135 93.345 0)
			(effects
				(font
					(size 1.27 1.27)
				)
			)
		)
		(property "MPN" ""
			(at 191.135 93.345 0)
			(effects
				(font
					(size 1.27 1.27)
				)
				(hide yes)
			)
		)
		(property "Manufacturer" ""
			(at 191.135 93.345 0)
			(effects
				(font
					(size 1.27 1.27)
				)
				(hide yes)
			)
		)
		(property "Author" "Antmicro"
			(at 175.895 108.585 0)
			(effects
				(font
					(size 1.27 1.27)
					(thickness 0.15)
				)
				(justify left bottom)
				(hide yes)
			)
		)
		(property "License" "Apache-2.0"
			(at 175.895 111.125 0)
			(effects
				(font
					(size 1.27 1.27)
					(thickness 0.15)
				)
				(justify left bottom)
				(hide yes)
			)
		)
		(pin "1"
		)
		(instances
			(project ""
				(path ""
					(reference "TP2")
					(unit 1)
				)
			)
		)
	)
	(symbol
		(lib_id "antmicropower:PWR_FLAG")
		(at 294.64 88.9 270)
		(unit 1)
		(exclude_from_sim no)
		(in_bom yes)
		(on_board yes)
		(dnp no)
		(property "Reference" "#FLG0104"
			(at 296.545 88.9 0)
			(effects
				(font
					(size 1.27 1.27)
				)
				(hide yes)
			)
		)
		(property "Value" "PWR_FLAG"
			(at 297.815 88.9 90)
			(effects
				(font
					(size 1.27 1.27)
				)
				(justify left)
			)
		)
		(property "Footprint" ""
			(at 294.64 88.9 0)
			(effects
				(font
					(size 1.27 1.27)
				)
				(hide yes)
			)
		)
		(property "Datasheet" ""
			(at 294.64 88.9 0)
			(effects
				(font
					(size 1.27 1.27)
				)
				(hide yes)
			)
		)
		(property "Description" ""
			(at 294.64 88.9 0)
			(effects
				(font
					(size 1.27 1.27)
				)
			)
		)
		(pin "1"
		)
		(instances
			(project ""
				(path ""
					(reference "#FLG0104")
					(unit 1)
				)
			)
		)
	)
	(symbol
		(lib_id "antmicropower:GND")
		(at 168.91 184.785 0)
		(unit 1)
		(exclude_from_sim no)
		(in_bom yes)
		(on_board yes)
		(dnp no)
		(fields_autoplaced yes)
		(property "Reference" "#PWR0157"
			(at 177.8 187.325 0)
			(effects
				(font
					(size 1.27 1.27)
					(thickness 0.15)
				)
				(justify left bottom)
				(hide yes)
			)
		)
		(property "Value" "GND"
			(at 168.91 189.23 0)
			(effects
				(font
					(size 1.27 1.27)
					(thickness 0.15)
				)
			)
		)
		(property "Footprint" ""
			(at 177.8 192.405 0)
			(effects
				(font
					(size 1.27 1.27)
					(thickness 0.15)
				)
				(justify left bottom)
				(hide yes)
			)
		)
		(property "Datasheet" ""
			(at 177.8 197.485 0)
			(effects
				(font
					(size 1.27 1.27)
					(thickness 0.15)
				)
				(justify left bottom)
				(hide yes)
			)
		)
		(property "Description" ""
			(at 168.91 184.785 0)
			(effects
				(font
					(size 1.27 1.27)
				)
			)
		)
		(property "Author" "Antmicro"
			(at 177.8 192.405 0)
			(effects
				(font
					(size 1.27 1.27)
					(thickness 0.15)
				)
				(justify left bottom)
				(hide yes)
			)
		)
		(property "License" "Apache-2.0"
			(at 177.8 194.945 0)
			(effects
				(font
					(size 1.27 1.27)
					(thickness 0.15)
				)
				(justify left bottom)
				(hide yes)
			)
		)
		(pin "1"
		)
		(instances
			(project ""
				(path ""
					(reference "#PWR0157")
					(unit 1)
				)
			)
		)
	)
	(symbol
		(lib_id "antmicroCapacitors0402:C_4u7_0402")
		(at 295.91 186.055 90)
		(unit 1)
		(exclude_from_sim no)
		(in_bom yes)
		(on_board yes)
		(dnp no)
		(property "Reference" "C20"
			(at 296.545 181.61 90)
			(effects
				(font
					(size 1.27 1.27)
					(thickness 0.15)
				)
				(justify right)
			)
		)
		(property "Value" "C_4u7_0402"
			(at 306.07 165.735 0)
			(effects
				(font
					(size 1.27 1.27)
					(thickness 0.15)
				)
				(justify left bottom)
				(hide yes)
			)
		)
		(property "Footprint" "antmicro-footprints:C_0402_1005Metric"
			(at 308.61 165.735 0)
			(effects
				(font
					(size 1.27 1.27)
					(thickness 0.15)
				)
				(justify left bottom)
				(hide yes)
			)
		)
		(property "Datasheet" "https://www.murata.com/products/productdetail?partno=GRM155R61A475MEAA%23"
			(at 311.15 165.735 0)
			(effects
				(font
					(size 1.27 1.27)
					(thickness 0.15)
				)
				(justify left bottom)
				(hide yes)
			)
		)
		(property "Description" ""
			(at 295.91 186.055 0)
			(effects
				(font
					(size 1.27 1.27)
				)
			)
		)
		(property "MPN" "GRM155R61A475MEAAD"
			(at 313.69 165.735 0)
			(effects
				(font
					(size 1.27 1.27)
					(thickness 0.15)
				)
				(justify left bottom)
				(hide yes)
			)
		)
		(property "Manufacturer" "Murata"
			(at 316.23 165.735 0)
			(effects
				(font
					(size 1.27 1.27)
					(thickness 0.15)
				)
				(justify left bottom)
				(hide yes)
			)
		)
		(property "License" "Apache-2.0"
			(at 318.77 165.735 0)
			(effects
				(font
					(size 1.27 1.27)
					(thickness 0.15)
				)
				(justify left bottom)
				(hide yes)
			)
		)
		(property "Author" "Antmicro"
			(at 321.31 165.735 0)
			(effects
				(font
					(size 1.27 1.27)
					(thickness 0.15)
				)
				(justify left bottom)
				(hide yes)
			)
		)
		(property "Val" "4u7"
			(at 296.545 185.42 90)
			(effects
				(font
					(size 1.27 1.27)
					(thickness 0.15)
				)
				(justify right)
			)
		)
		(property "Voltage" ""
			(at 323.85 165.735 0)
			(effects
				(font
					(size 1.27 1.27)
				)
				(justify left bottom)
				(hide yes)
			)
		)
		(property "Dielectric" ""
			(at 326.39 165.735 0)
			(effects
				(font
					(size 1.27 1.27)
				)
				(justify left bottom)
				(hide yes)
			)
		)
		(pin "1"
		)
		(pin "2"
		)
		(instances
			(project ""
				(path ""
					(reference "C20")
					(unit 1)
				)
			)
		)
	)
	(symbol
		(lib_id "antmicropower:GND")
		(at 266.7 110.49 0)
		(unit 1)
		(exclude_from_sim no)
		(in_bom yes)
		(on_board yes)
		(dnp no)
		(fields_autoplaced yes)
		(property "Reference" "#PWR0153"
			(at 275.59 113.03 0)
			(effects
				(font
					(size 1.27 1.27)
					(thickness 0.15)
				)
				(justify left bottom)
				(hide yes)
			)
		)
		(property "Value" "GND"
			(at 266.7 114.935 0)
			(effects
				(font
					(size 1.27 1.27)
					(thickness 0.15)
				)
			)
		)
		(property "Footprint" ""
			(at 275.59 118.11 0)
			(effects
				(font
					(size 1.27 1.27)
					(thickness 0.15)
				)
				(justify left bottom)
				(hide yes)
			)
		)
		(property "Datasheet" ""
			(at 275.59 123.19 0)
			(effects
				(font
					(size 1.27 1.27)
					(thickness 0.15)
				)
				(justify left bottom)
				(hide yes)
			)
		)
		(property "Description" ""
			(at 266.7 110.49 0)
			(effects
				(font
					(size 1.27 1.27)
				)
			)
		)
		(property "Author" "Antmicro"
			(at 275.59 118.11 0)
			(effects
				(font
					(size 1.27 1.27)
					(thickness 0.15)
				)
				(justify left bottom)
				(hide yes)
			)
		)
		(property "License" "Apache-2.0"
			(at 275.59 120.65 0)
			(effects
				(font
					(size 1.27 1.27)
					(thickness 0.15)
				)
				(justify left bottom)
				(hide yes)
			)
		)
		(pin "1"
		)
		(instances
			(project ""
				(path ""
					(reference "#PWR0153")
					(unit 1)
				)
			)
		)
	)
	(symbol
		(lib_id "antmicropower:+1V1")
		(at 231.14 193.675 0)
		(unit 1)
		(exclude_from_sim no)
		(in_bom yes)
		(on_board yes)
		(dnp no)
		(fields_autoplaced yes)
		(property "Reference" "#PWR0102"
			(at 231.14 197.485 0)
			(effects
				(font
					(size 1.27 1.27)
				)
				(hide yes)
			)
		)
		(property "Value" "+1V1"
			(at 231.14 188.595 0)
			(effects
				(font
					(size 1.27 1.27)
				)
			)
		)
		(property "Footprint" ""
			(at 231.14 193.675 0)
			(effects
				(font
					(size 1.27 1.27)
				)
				(hide yes)
			)
		)
		(property "Datasheet" ""
			(at 231.14 193.675 0)
			(effects
				(font
					(size 1.27 1.27)
				)
				(hide yes)
			)
		)
		(property "Description" ""
			(at 231.14 193.675 0)
			(effects
				(font
					(size 1.27 1.27)
				)
			)
		)
		(pin "1"
		)
		(instances
			(project ""
				(path ""
					(reference "#PWR0102")
					(unit 1)
				)
			)
		)
	)
	(symbol
		(lib_id "antmicropower:+0V5")
		(at 342.265 177.165 0)
		(unit 1)
		(exclude_from_sim no)
		(in_bom yes)
		(on_board yes)
		(dnp no)
		(fields_autoplaced yes)
		(property "Reference" "#PWR0167"
			(at 342.265 180.975 0)
			(effects
				(font
					(size 1.27 1.27)
				)
				(hide yes)
			)
		)
		(property "Value" "+0V5"
			(at 342.265 171.45 0)
			(effects
				(font
					(size 1.27 1.27)
				)
			)
		)
		(property "Footprint" ""
			(at 342.265 177.165 0)
			(effects
				(font
					(size 1.27 1.27)
				)
				(hide yes)
			)
		)
		(property "Datasheet" ""
			(at 342.265 177.165 0)
			(effects
				(font
					(size 1.27 1.27)
				)
				(hide yes)
			)
		)
		(property "Description" ""
			(at 342.265 177.165 0)
			(effects
				(font
					(size 1.27 1.27)
				)
			)
		)
		(pin "1"
		)
		(instances
			(project ""
				(path ""
					(reference "#PWR0167")
					(unit 1)
				)
			)
		)
	)
	(symbol
		(lib_id "antmicroResistors0402:R_0R_0402")
		(at 184.15 171.45 90)
		(unit 1)
		(exclude_from_sim no)
		(in_bom yes)
		(on_board yes)
		(dnp no)
		(property "Reference" "R3"
			(at 182.88 166.37 0)
			(effects
				(font
					(size 1.27 1.27)
					(thickness 0.15)
				)
				(justify left)
			)
		)
		(property "Value" "R_0R_0402"
			(at 196.85 151.13 0)
			(effects
				(font
					(size 1.27 1.27)
					(thickness 0.15)
				)
				(justify left bottom)
				(hide yes)
			)
		)
		(property "Footprint" "antmicro-footprints:R_0402_1005Metric"
			(at 199.39 151.13 0)
			(effects
				(font
					(size 1.27 1.27)
					(thickness 0.15)
				)
				(justify left bottom)
				(hide yes)
			)
		)
		(property "Datasheet" "https://industrial.panasonic.com/cdbs/www-data/pdf/RDA0000/AOA0000C301.pdf"
			(at 201.93 151.13 0)
			(effects
				(font
					(size 1.27 1.27)
					(thickness 0.15)
				)
				(justify left bottom)
				(hide yes)
			)
		)
		(property "Description" ""
			(at 184.15 171.45 0)
			(effects
				(font
					(size 1.27 1.27)
				)
			)
		)
		(property "MPN" "ERJ2GE0R00X"
			(at 204.47 151.13 0)
			(effects
				(font
					(size 1.27 1.27)
					(thickness 0.15)
				)
				(justify left bottom)
				(hide yes)
			)
		)
		(property "Manufacturer" "Panasonic"
			(at 207.01 151.13 0)
			(effects
				(font
					(size 1.27 1.27)
					(thickness 0.15)
				)
				(justify left bottom)
				(hide yes)
			)
		)
		(property "License" "Apache-2.0"
			(at 209.55 151.13 0)
			(effects
				(font
					(size 1.27 1.27)
					(thickness 0.15)
				)
				(justify left bottom)
				(hide yes)
			)
		)
		(property "Author" "Antmicro"
			(at 212.09 151.13 0)
			(effects
				(font
					(size 1.27 1.27)
					(thickness 0.15)
				)
				(justify left bottom)
				(hide yes)
			)
		)
		(property "Val" "0R"
			(at 182.88 172.72 0)
			(effects
				(font
					(size 1.27 1.27)
					(thickness 0.15)
				)
			)
		)
		(property "Tolerance" "~"
			(at 194.31 151.13 0)
			(effects
				(font
					(size 1.27 1.27)
				)
				(justify left bottom)
				(hide yes)
			)
		)
		(property "Current" "1A"
			(at 214.63 151.13 0)
			(effects
				(font
					(size 1.27 1.27)
					(thickness 0.15)
				)
				(justify left bottom)
				(hide yes)
			)
		)
		(pin "1"
		)
		(pin "2"
		)
		(instances
			(project ""
				(path ""
					(reference "R3")
					(unit 1)
				)
			)
		)
	)
	(symbol
		(lib_id "antmicropower:GND")
		(at 196.85 197.485 0)
		(unit 1)
		(exclude_from_sim no)
		(in_bom yes)
		(on_board yes)
		(dnp no)
		(property "Reference" "#PWR0163"
			(at 205.74 200.025 0)
			(effects
				(font
					(size 1.27 1.27)
					(thickness 0.15)
				)
				(justify left bottom)
				(hide yes)
			)
		)
		(property "Value" "GND"
			(at 196.85 201.295 0)
			(effects
				(font
					(size 1.27 1.27)
					(thickness 0.15)
				)
			)
		)
		(property "Footprint" ""
			(at 205.74 205.105 0)
			(effects
				(font
					(size 1.27 1.27)
					(thickness 0.15)
				)
				(justify left bottom)
				(hide yes)
			)
		)
		(property "Datasheet" ""
			(at 205.74 210.185 0)
			(effects
				(font
					(size 1.27 1.27)
					(thickness 0.15)
				)
				(justify left bottom)
				(hide yes)
			)
		)
		(property "Description" ""
			(at 196.85 197.485 0)
			(effects
				(font
					(size 1.27 1.27)
				)
			)
		)
		(property "Author" "Antmicro"
			(at 205.74 205.105 0)
			(effects
				(font
					(size 1.27 1.27)
					(thickness 0.15)
				)
				(justify left bottom)
				(hide yes)
			)
		)
		(property "License" "Apache-2.0"
			(at 205.74 207.645 0)
			(effects
				(font
					(size 1.27 1.27)
					(thickness 0.15)
				)
				(justify left bottom)
				(hide yes)
			)
		)
		(pin "1"
		)
		(instances
			(project ""
				(path ""
					(reference "#PWR0163")
					(unit 1)
				)
			)
		)
	)
	(symbol
		(lib_id "antmicropower:GND")
		(at 276.225 201.295 0)
		(unit 1)
		(exclude_from_sim no)
		(in_bom yes)
		(on_board yes)
		(dnp no)
		(property "Reference" "#PWR0206"
			(at 285.115 203.835 0)
			(effects
				(font
					(size 1.27 1.27)
					(thickness 0.15)
				)
				(justify left bottom)
				(hide yes)
			)
		)
		(property "Value" "GND"
			(at 280.035 202.565 0)
			(effects
				(font
					(size 1.27 1.27)
					(thickness 0.15)
				)
			)
		)
		(property "Footprint" ""
			(at 285.115 208.915 0)
			(effects
				(font
					(size 1.27 1.27)
					(thickness 0.15)
				)
				(justify left bottom)
				(hide yes)
			)
		)
		(property "Datasheet" ""
			(at 285.115 213.995 0)
			(effects
				(font
					(size 1.27 1.27)
					(thickness 0.15)
				)
				(justify left bottom)
				(hide yes)
			)
		)
		(property "Description" ""
			(at 276.225 201.295 0)
			(effects
				(font
					(size 1.27 1.27)
				)
			)
		)
		(property "Author" "Antmicro"
			(at 285.115 208.915 0)
			(effects
				(font
					(size 1.27 1.27)
					(thickness 0.15)
				)
				(justify left bottom)
				(hide yes)
			)
		)
		(property "License" "Apache-2.0"
			(at 285.115 211.455 0)
			(effects
				(font
					(size 1.27 1.27)
					(thickness 0.15)
				)
				(justify left bottom)
				(hide yes)
			)
		)
		(pin "1"
		)
		(instances
			(project ""
				(path ""
					(reference "#PWR0206")
					(unit 1)
				)
			)
		)
	)
	(symbol
		(lib_id "antmicroCapacitors0603:C_22u_0603")
		(at 266.7 80.645 90)
		(unit 1)
		(exclude_from_sim no)
		(in_bom yes)
		(on_board yes)
		(dnp no)
		(property "Reference" "C16"
			(at 267.335 76.2 90)
			(effects
				(font
					(size 1.27 1.27)
					(thickness 0.15)
				)
				(justify right)
			)
		)
		(property "Value" "C_22u_0603"
			(at 276.86 60.325 0)
			(effects
				(font
					(size 1.27 1.27)
					(thickness 0.15)
				)
				(justify left bottom)
				(hide yes)
			)
		)
		(property "Footprint" "antmicro-footprints:C_0603_1608Metric"
			(at 279.4 60.325 0)
			(effects
				(font
					(size 1.27 1.27)
					(thickness 0.15)
				)
				(justify left bottom)
				(hide yes)
			)
		)
		(property "Datasheet" "https://www.murata.com/products/productdetail?partno=GRM188R60J226MEA0%23"
			(at 281.94 60.325 0)
			(effects
				(font
					(size 1.27 1.27)
					(thickness 0.15)
				)
				(justify left bottom)
				(hide yes)
			)
		)
		(property "Description" ""
			(at 266.7 80.645 0)
			(effects
				(font
					(size 1.27 1.27)
				)
			)
		)
		(property "MPN" "GRM188R60J226MEA0D"
			(at 284.48 60.325 0)
			(effects
				(font
					(size 1.27 1.27)
					(thickness 0.15)
				)
				(justify left bottom)
				(hide yes)
			)
		)
		(property "Manufacturer" "Murata"
			(at 287.02 60.325 0)
			(effects
				(font
					(size 1.27 1.27)
					(thickness 0.15)
				)
				(justify left bottom)
				(hide yes)
			)
		)
		(property "License" "Apache-2.0"
			(at 289.56 60.325 0)
			(effects
				(font
					(size 1.27 1.27)
					(thickness 0.15)
				)
				(justify left bottom)
				(hide yes)
			)
		)
		(property "Author" "Antmicro"
			(at 292.1 60.325 0)
			(effects
				(font
					(size 1.27 1.27)
					(thickness 0.15)
				)
				(justify left bottom)
				(hide yes)
			)
		)
		(property "Val" "22u"
			(at 267.335 80.01 90)
			(effects
				(font
					(size 1.27 1.27)
					(thickness 0.15)
				)
				(justify right)
			)
		)
		(property "Voltage" ""
			(at 294.64 60.325 0)
			(effects
				(font
					(size 1.27 1.27)
				)
				(justify left bottom)
				(hide yes)
			)
		)
		(property "Dielectric" ""
			(at 297.18 60.325 0)
			(effects
				(font
					(size 1.27 1.27)
				)
				(justify left bottom)
				(hide yes)
			)
		)
		(pin "1"
		)
		(pin "2"
		)
		(instances
			(project ""
				(path ""
					(reference "C16")
					(unit 1)
				)
			)
		)
	)
	(symbol
		(lib_id "antmicroResistors0402:R_130k_0402")
		(at 236.22 106.68 0)
		(unit 1)
		(exclude_from_sim no)
		(in_bom yes)
		(on_board yes)
		(dnp no)
		(property "Reference" "R38"
			(at 234.315 105.41 0)
			(effects
				(font
					(size 1.27 1.27)
					(thickness 0.15)
				)
			)
		)
		(property "Value" "R_130k_0402"
			(at 256.54 119.38 0)
			(effects
				(font
					(size 1.27 1.27)
					(thickness 0.15)
				)
				(justify left bottom)
				(hide yes)
			)
		)
		(property "Footprint" "antmicro-footprints:R_0402_1005Metric"
			(at 256.54 121.92 0)
			(effects
				(font
					(size 1.27 1.27)
					(thickness 0.15)
				)
				(justify left bottom)
				(hide yes)
			)
		)
		(property "Datasheet" "https://www.bourns.com/docs/product-datasheets/cr.pdf"
			(at 256.54 124.46 0)
			(effects
				(font
					(size 1.27 1.27)
					(thickness 0.15)
				)
				(justify left bottom)
				(hide yes)
			)
		)
		(property "Description" ""
			(at 236.22 106.68 0)
			(effects
				(font
					(size 1.27 1.27)
				)
			)
		)
		(property "MPN" "CR0402-FX-1303GLF"
			(at 256.54 127 0)
			(effects
				(font
					(size 1.27 1.27)
					(thickness 0.15)
				)
				(justify left bottom)
				(hide yes)
			)
		)
		(property "Manufacturer" "Bourns"
			(at 256.54 129.54 0)
			(effects
				(font
					(size 1.27 1.27)
					(thickness 0.15)
				)
				(justify left bottom)
				(hide yes)
			)
		)
		(property "License" "Apache-2.0"
			(at 256.54 132.08 0)
			(effects
				(font
					(size 1.27 1.27)
					(thickness 0.15)
				)
				(justify left bottom)
				(hide yes)
			)
		)
		(property "Author" "Antmicro"
			(at 256.54 134.62 0)
			(effects
				(font
					(size 1.27 1.27)
					(thickness 0.15)
				)
				(justify left bottom)
				(hide yes)
			)
		)
		(property "Val" "130k"
			(at 243.205 105.41 0)
			(effects
				(font
					(size 1.27 1.27)
					(thickness 0.15)
				)
			)
		)
		(property "Tolerance" "1%"
			(at 256.54 116.84 0)
			(effects
				(font
					(size 1.27 1.27)
				)
				(justify left bottom)
				(hide yes)
			)
		)
		(pin "1"
		)
		(pin "2"
		)
		(instances
			(project ""
				(path ""
					(reference "R38")
					(unit 1)
				)
			)
		)
	)
	(symbol
		(lib_id "antmicroTestPoints:TP_0.75mm_SMD")
		(at 319.405 176.53 90)
		(unit 1)
		(exclude_from_sim no)
		(in_bom yes)
		(on_board yes)
		(dnp no)
		(property "Reference" "TP8"
			(at 316.865 172.72 0)
			(effects
				(font
					(size 1.27 1.27)
					(thickness 0.15)
				)
			)
		)
		(property "Value" "TP_0.75mm_SMD"
			(at 323.215 165.735 0)
			(effects
				(font
					(size 1.27 1.27)
					(thickness 0.15)
				)
				(justify left bottom)
				(hide yes)
			)
		)
		(property "Footprint" "antmicro-footprints:TP_SMD_0.75mm"
			(at 325.755 165.735 0)
			(effects
				(font
					(size 1.27 1.27)
					(thickness 0.15)
				)
				(justify left bottom)
				(hide yes)
			)
		)
		(property "Datasheet" ""
			(at 332.105 158.75 0)
			(effects
				(font
					(size 1.27 1.27)
					(thickness 0.15)
				)
				(justify left bottom)
				(hide yes)
			)
		)
		(property "Description" ""
			(at 319.405 176.53 0)
			(effects
				(font
					(size 1.27 1.27)
				)
			)
		)
		(property "MPN" ""
			(at 330.835 165.735 0)
			(effects
				(font
					(size 1.27 1.27)
					(thickness 0.15)
				)
				(justify left bottom)
				(hide yes)
			)
		)
		(property "Manufacturer" ""
			(at 325.755 165.735 0)
			(effects
				(font
					(size 1.27 1.27)
					(thickness 0.15)
				)
				(justify left bottom)
				(hide yes)
			)
		)
		(property "Author" "Antmicro"
			(at 328.295 165.735 0)
			(effects
				(font
					(size 1.27 1.27)
					(thickness 0.15)
				)
				(justify left bottom)
				(hide yes)
			)
		)
		(property "License" "Apache-2.0"
			(at 330.835 165.735 0)
			(effects
				(font
					(size 1.27 1.27)
					(thickness 0.15)
				)
				(justify left bottom)
				(hide yes)
			)
		)
		(pin "1"
		)
		(instances
			(project ""
				(path ""
					(reference "TP8")
					(unit 1)
				)
			)
		)
	)
	(symbol
		(lib_id "antmicropower:GND")
		(at 180.975 64.135 0)
		(unit 1)
		(exclude_from_sim no)
		(in_bom yes)
		(on_board yes)
		(dnp no)
		(property "Reference" "#PWR0219"
			(at 189.865 66.675 0)
			(effects
				(font
					(size 1.27 1.27)
					(thickness 0.15)
				)
				(justify left bottom)
				(hide yes)
			)
		)
		(property "Value" "GND"
			(at 180.975 67.945 0)
			(effects
				(font
					(size 1.27 1.27)
					(thickness 0.15)
				)
			)
		)
		(property "Footprint" ""
			(at 189.865 71.755 0)
			(effects
				(font
					(size 1.27 1.27)
					(thickness 0.15)
				)
				(justify left bottom)
				(hide yes)
			)
		)
		(property "Datasheet" ""
			(at 189.865 76.835 0)
			(effects
				(font
					(size 1.27 1.27)
					(thickness 0.15)
				)
				(justify left bottom)
				(hide yes)
			)
		)
		(property "Description" ""
			(at 180.975 64.135 0)
			(effects
				(font
					(size 1.27 1.27)
				)
			)
		)
		(property "Author" "Antmicro"
			(at 189.865 71.755 0)
			(effects
				(font
					(size 1.27 1.27)
					(thickness 0.15)
				)
				(justify left bottom)
				(hide yes)
			)
		)
		(property "License" "Apache-2.0"
			(at 189.865 74.295 0)
			(effects
				(font
					(size 1.27 1.27)
					(thickness 0.15)
				)
				(justify left bottom)
				(hide yes)
			)
		)
		(pin "1"
		)
		(instances
			(project ""
				(path ""
					(reference "#PWR0219")
					(unit 1)
				)
			)
		)
	)
	(symbol
		(lib_id "antmicropower:GND")
		(at 295.91 187.325 0)
		(unit 1)
		(exclude_from_sim no)
		(in_bom yes)
		(on_board yes)
		(dnp no)
		(fields_autoplaced yes)
		(property "Reference" "#PWR0204"
			(at 304.8 189.865 0)
			(effects
				(font
					(size 1.27 1.27)
					(thickness 0.15)
				)
				(justify left bottom)
				(hide yes)
			)
		)
		(property "Value" "GND"
			(at 295.91 191.77 0)
			(effects
				(font
					(size 1.27 1.27)
					(thickness 0.15)
				)
			)
		)
		(property "Footprint" ""
			(at 304.8 194.945 0)
			(effects
				(font
					(size 1.27 1.27)
					(thickness 0.15)
				)
				(justify left bottom)
				(hide yes)
			)
		)
		(property "Datasheet" ""
			(at 304.8 200.025 0)
			(effects
				(font
					(size 1.27 1.27)
					(thickness 0.15)
				)
				(justify left bottom)
				(hide yes)
			)
		)
		(property "Description" ""
			(at 295.91 187.325 0)
			(effects
				(font
					(size 1.27 1.27)
				)
			)
		)
		(property "Author" "Antmicro"
			(at 304.8 194.945 0)
			(effects
				(font
					(size 1.27 1.27)
					(thickness 0.15)
				)
				(justify left bottom)
				(hide yes)
			)
		)
		(property "License" "Apache-2.0"
			(at 304.8 197.485 0)
			(effects
				(font
					(size 1.27 1.27)
					(thickness 0.15)
				)
				(justify left bottom)
				(hide yes)
			)
		)
		(pin "1"
		)
		(instances
			(project ""
				(path ""
					(reference "#PWR0204")
					(unit 1)
				)
			)
		)
	)
	(symbol
		(lib_id "antmicroResistors0402:R_0R_0402")
		(at 163.83 197.485 0)
		(unit 1)
		(exclude_from_sim no)
		(in_bom no)
		(on_board yes)
		(dnp yes)
		(property "Reference" "R29"
			(at 168.91 196.215 0)
			(effects
				(font
					(size 1.27 1.27)
					(thickness 0.15)
				)
				(justify left)
			)
		)
		(property "Value" "R_0R_0402"
			(at 184.15 210.185 0)
			(effects
				(font
					(size 1.27 1.27)
					(thickness 0.15)
				)
				(justify left bottom)
				(hide yes)
			)
		)
		(property "Footprint" "antmicro-footprints:R_0402_1005Metric"
			(at 184.15 212.725 0)
			(effects
				(font
					(size 1.27 1.27)
					(thickness 0.15)
				)
				(justify left bottom)
				(hide yes)
			)
		)
		(property "Datasheet" "https://industrial.panasonic.com/cdbs/www-data/pdf/RDA0000/AOA0000C301.pdf"
			(at 184.15 215.265 0)
			(effects
				(font
					(size 1.27 1.27)
					(thickness 0.15)
				)
				(justify left bottom)
				(hide yes)
			)
		)
		(property "Description" ""
			(at 163.83 197.485 0)
			(effects
				(font
					(size 1.27 1.27)
				)
			)
		)
		(property "MPN" "ERJ2GE0R00X"
			(at 184.15 217.805 0)
			(effects
				(font
					(size 1.27 1.27)
					(thickness 0.15)
				)
				(justify left bottom)
				(hide yes)
			)
		)
		(property "Manufacturer" "Panasonic"
			(at 184.15 220.345 0)
			(effects
				(font
					(size 1.27 1.27)
					(thickness 0.15)
				)
				(justify left bottom)
				(hide yes)
			)
		)
		(property "License" "Apache-2.0"
			(at 184.15 222.885 0)
			(effects
				(font
					(size 1.27 1.27)
					(thickness 0.15)
				)
				(justify left bottom)
				(hide yes)
			)
		)
		(property "Author" "Antmicro"
			(at 184.15 225.425 0)
			(effects
				(font
					(size 1.27 1.27)
					(thickness 0.15)
				)
				(justify left bottom)
				(hide yes)
			)
		)
		(property "Val" "0R"
			(at 162.56 196.215 0)
			(effects
				(font
					(size 1.27 1.27)
					(thickness 0.15)
				)
			)
		)
		(property "Tolerance" "~"
			(at 184.15 207.645 0)
			(effects
				(font
					(size 1.27 1.27)
				)
				(justify left bottom)
				(hide yes)
			)
		)
		(property "Current" "1A"
			(at 184.15 227.965 0)
			(effects
				(font
					(size 1.27 1.27)
					(thickness 0.15)
				)
				(justify left bottom)
				(hide yes)
			)
		)
		(pin "1"
		)
		(pin "2"
		)
		(instances
			(project ""
				(path ""
					(reference "R29")
					(unit 1)
				)
			)
		)
	)
	(symbol
		(lib_id "antmicropower:GND")
		(at 193.04 115.57 0)
		(unit 1)
		(exclude_from_sim no)
		(in_bom yes)
		(on_board yes)
		(dnp no)
		(property "Reference" "#PWR0214"
			(at 201.93 118.11 0)
			(effects
				(font
					(size 1.27 1.27)
					(thickness 0.15)
				)
				(justify left bottom)
				(hide yes)
			)
		)
		(property "Value" "GND"
			(at 193.04 119.38 0)
			(effects
				(font
					(size 1.27 1.27)
					(thickness 0.15)
				)
			)
		)
		(property "Footprint" ""
			(at 201.93 123.19 0)
			(effects
				(font
					(size 1.27 1.27)
					(thickness 0.15)
				)
				(justify left bottom)
				(hide yes)
			)
		)
		(property "Datasheet" ""
			(at 201.93 128.27 0)
			(effects
				(font
					(size 1.27 1.27)
					(thickness 0.15)
				)
				(justify left bottom)
				(hide yes)
			)
		)
		(property "Description" ""
			(at 193.04 115.57 0)
			(effects
				(font
					(size 1.27 1.27)
				)
			)
		)
		(property "Author" "Antmicro"
			(at 201.93 123.19 0)
			(effects
				(font
					(size 1.27 1.27)
					(thickness 0.15)
				)
				(justify left bottom)
				(hide yes)
			)
		)
		(property "License" "Apache-2.0"
			(at 201.93 125.73 0)
			(effects
				(font
					(size 1.27 1.27)
					(thickness 0.15)
				)
				(justify left bottom)
				(hide yes)
			)
		)
		(pin "1"
		)
		(instances
			(project ""
				(path ""
					(reference "#PWR0214")
					(unit 1)
				)
			)
		)
	)
	(symbol
		(lib_id "antmicropower:GND")
		(at 257.81 95.25 0)
		(unit 1)
		(exclude_from_sim no)
		(in_bom yes)
		(on_board yes)
		(dnp no)
		(fields_autoplaced yes)
		(property "Reference" "#PWR0224"
			(at 266.7 97.79 0)
			(effects
				(font
					(size 1.27 1.27)
					(thickness 0.15)
				)
				(justify left bottom)
				(hide yes)
			)
		)
		(property "Value" "GND"
			(at 257.81 99.695 0)
			(effects
				(font
					(size 1.27 1.27)
					(thickness 0.15)
				)
			)
		)
		(property "Footprint" ""
			(at 266.7 102.87 0)
			(effects
				(font
					(size 1.27 1.27)
					(thickness 0.15)
				)
				(justify left bottom)
				(hide yes)
			)
		)
		(property "Datasheet" ""
			(at 266.7 107.95 0)
			(effects
				(font
					(size 1.27 1.27)
					(thickness 0.15)
				)
				(justify left bottom)
				(hide yes)
			)
		)
		(property "Description" ""
			(at 257.81 95.25 0)
			(effects
				(font
					(size 1.27 1.27)
				)
			)
		)
		(property "Author" "Antmicro"
			(at 266.7 102.87 0)
			(effects
				(font
					(size 1.27 1.27)
					(thickness 0.15)
				)
				(justify left bottom)
				(hide yes)
			)
		)
		(property "License" "Apache-2.0"
			(at 266.7 105.41 0)
			(effects
				(font
					(size 1.27 1.27)
					(thickness 0.15)
				)
				(justify left bottom)
				(hide yes)
			)
		)
		(pin "1"
		)
		(instances
			(project ""
				(path ""
					(reference "#PWR0224")
					(unit 1)
				)
			)
		)
	)
	(symbol
		(lib_id "antmicroResistors0402:R_25k5_0402")
		(at 231.14 207.01 90)
		(unit 1)
		(exclude_from_sim no)
		(in_bom yes)
		(on_board yes)
		(dnp no)
		(property "Reference" "R41"
			(at 232.41 203.2 90)
			(effects
				(font
					(size 1.27 1.27)
					(thickness 0.15)
				)
				(justify right)
			)
		)
		(property "Value" "R_25k5_0402"
			(at 243.84 186.69 0)
			(effects
				(font
					(size 1.27 1.27)
					(thickness 0.15)
				)
				(justify left bottom)
				(hide yes)
			)
		)
		(property "Footprint" "antmicro-footprints:R_0402_1005Metric"
			(at 246.38 186.69 0)
			(effects
				(font
					(size 1.27 1.27)
					(thickness 0.15)
				)
				(justify left bottom)
				(hide yes)
			)
		)
		(property "Datasheet" "https://www.bourns.com/docs/product-datasheets/cr.pdf"
			(at 248.92 186.69 0)
			(effects
				(font
					(size 1.27 1.27)
					(thickness 0.15)
				)
				(justify left bottom)
				(hide yes)
			)
		)
		(property "Description" ""
			(at 231.14 207.01 0)
			(effects
				(font
					(size 1.27 1.27)
				)
			)
		)
		(property "MPN" "CR0402-FX-2552GLF"
			(at 251.46 186.69 0)
			(effects
				(font
					(size 1.27 1.27)
					(thickness 0.15)
				)
				(justify left bottom)
				(hide yes)
			)
		)
		(property "Manufacturer" "Bourns"
			(at 254 186.69 0)
			(effects
				(font
					(size 1.27 1.27)
					(thickness 0.15)
				)
				(justify left bottom)
				(hide yes)
			)
		)
		(property "License" "Apache-2.0"
			(at 256.54 186.69 0)
			(effects
				(font
					(size 1.27 1.27)
					(thickness 0.15)
				)
				(justify left bottom)
				(hide yes)
			)
		)
		(property "Author" "Antmicro"
			(at 259.08 186.69 0)
			(effects
				(font
					(size 1.27 1.27)
					(thickness 0.15)
				)
				(justify left bottom)
				(hide yes)
			)
		)
		(property "Val" "25k5"
			(at 232.41 205.74 90)
			(effects
				(font
					(size 1.27 1.27)
					(thickness 0.15)
				)
				(justify right)
			)
		)
		(property "Tolerance" "1%"
			(at 241.3 186.69 0)
			(effects
				(font
					(size 1.27 1.27)
				)
				(justify left bottom)
				(hide yes)
			)
		)
		(pin "1"
		)
		(pin "2"
		)
		(instances
			(project ""
				(path ""
					(reference "R41")
					(unit 1)
				)
			)
		)
	)
	(symbol
		(lib_id "antmicroResistors0402:R_100k_0402")
		(at 236.22 114.3 0)
		(unit 1)
		(exclude_from_sim no)
		(in_bom yes)
		(on_board yes)
		(dnp no)
		(property "Reference" "R39"
			(at 234.95 113.03 0)
			(effects
				(font
					(size 1.27 1.27)
					(thickness 0.15)
				)
			)
		)
		(property "Value" "R_100k_0402"
			(at 256.54 127 0)
			(effects
				(font
					(size 1.27 1.27)
					(thickness 0.15)
				)
				(justify left bottom)
				(hide yes)
			)
		)
		(property "Footprint" "antmicro-footprints:R_0402_1005Metric"
			(at 256.54 129.54 0)
			(effects
				(font
					(size 1.27 1.27)
					(thickness 0.15)
				)
				(justify left bottom)
				(hide yes)
			)
		)
		(property "Datasheet" "https://www.bourns.com/docs/product-datasheets/cr.pdf"
			(at 256.54 132.08 0)
			(effects
				(font
					(size 1.27 1.27)
					(thickness 0.15)
				)
				(justify left bottom)
				(hide yes)
			)
		)
		(property "Description" ""
			(at 236.22 114.3 0)
			(effects
				(font
					(size 1.27 1.27)
				)
			)
		)
		(property "MPN" "CR0402-FX-1003GLF"
			(at 256.54 134.62 0)
			(effects
				(font
					(size 1.27 1.27)
					(thickness 0.15)
				)
				(justify left bottom)
				(hide yes)
			)
		)
		(property "Manufacturer" "Bourns"
			(at 256.54 137.16 0)
			(effects
				(font
					(size 1.27 1.27)
					(thickness 0.15)
				)
				(justify left bottom)
				(hide yes)
			)
		)
		(property "License" "Apache-2.0"
			(at 256.54 139.7 0)
			(effects
				(font
					(size 1.27 1.27)
					(thickness 0.15)
				)
				(justify left bottom)
				(hide yes)
			)
		)
		(property "Author" "Antmicro"
			(at 256.54 142.24 0)
			(effects
				(font
					(size 1.27 1.27)
					(thickness 0.15)
				)
				(justify left bottom)
				(hide yes)
			)
		)
		(property "Val" "100k"
			(at 243.205 113.03 0)
			(effects
				(font
					(size 1.27 1.27)
					(thickness 0.15)
				)
			)
		)
		(property "Tolerance" "1%"
			(at 256.54 124.46 0)
			(effects
				(font
					(size 1.27 1.27)
				)
				(justify left bottom)
				(hide yes)
			)
		)
		(pin "1"
		)
		(pin "2"
		)
		(instances
			(project ""
				(path ""
					(reference "R39")
					(unit 1)
				)
			)
		)
	)
	(symbol
		(lib_id "antmicropower:GND")
		(at 162.56 184.785 0)
		(unit 1)
		(exclude_from_sim no)
		(in_bom yes)
		(on_board yes)
		(dnp no)
		(fields_autoplaced yes)
		(property "Reference" "#PWR0158"
			(at 171.45 187.325 0)
			(effects
				(font
					(size 1.27 1.27)
					(thickness 0.15)
				)
				(justify left bottom)
				(hide yes)
			)
		)
		(property "Value" "GND"
			(at 162.56 189.23 0)
			(effects
				(font
					(size 1.27 1.27)
					(thickness 0.15)
				)
			)
		)
		(property "Footprint" ""
			(at 171.45 192.405 0)
			(effects
				(font
					(size 1.27 1.27)
					(thickness 0.15)
				)
				(justify left bottom)
				(hide yes)
			)
		)
		(property "Datasheet" ""
			(at 171.45 197.485 0)
			(effects
				(font
					(size 1.27 1.27)
					(thickness 0.15)
				)
				(justify left bottom)
				(hide yes)
			)
		)
		(property "Description" ""
			(at 162.56 184.785 0)
			(effects
				(font
					(size 1.27 1.27)
				)
			)
		)
		(property "Author" "Antmicro"
			(at 171.45 192.405 0)
			(effects
				(font
					(size 1.27 1.27)
					(thickness 0.15)
				)
				(justify left bottom)
				(hide yes)
			)
		)
		(property "License" "Apache-2.0"
			(at 171.45 194.945 0)
			(effects
				(font
					(size 1.27 1.27)
					(thickness 0.15)
				)
				(justify left bottom)
				(hide yes)
			)
		)
		(pin "1"
		)
		(instances
			(project ""
				(path ""
					(reference "#PWR0158")
					(unit 1)
				)
			)
		)
	)
	(symbol
		(lib_id "antmicropower:+5V")
		(at 159.385 56.515 0)
		(unit 1)
		(exclude_from_sim no)
		(in_bom yes)
		(on_board yes)
		(dnp no)
		(property "Reference" "#PWR0217"
			(at 174.625 59.055 0)
			(effects
				(font
					(size 1.27 1.27)
					(thickness 0.15)
				)
				(justify left bottom)
				(hide yes)
			)
		)
		(property "Value" "+5V"
			(at 159.385 52.705 0)
			(effects
				(font
					(size 1.27 1.27)
					(thickness 0.15)
				)
			)
		)
		(property "Footprint" ""
			(at 174.625 64.135 0)
			(effects
				(font
					(size 1.27 1.27)
					(thickness 0.15)
				)
				(justify left bottom)
				(hide yes)
			)
		)
		(property "Datasheet" ""
			(at 174.625 66.675 0)
			(effects
				(font
					(size 1.27 1.27)
					(thickness 0.15)
				)
				(justify left bottom)
				(hide yes)
			)
		)
		(property "Description" ""
			(at 159.385 56.515 0)
			(effects
				(font
					(size 1.27 1.27)
				)
			)
		)
		(property "Author" "Antmicro"
			(at 174.625 64.135 0)
			(effects
				(font
					(size 1.27 1.27)
					(thickness 0.15)
				)
				(justify left bottom)
				(hide yes)
			)
		)
		(property "License" "Apache-2.0"
			(at 174.625 66.675 0)
			(effects
				(font
					(size 1.27 1.27)
					(thickness 0.15)
				)
				(justify left bottom)
				(hide yes)
			)
		)
		(pin "1"
		)
		(instances
			(project ""
				(path ""
					(reference "#PWR0217")
					(unit 1)
				)
			)
		)
	)
	(symbol
		(lib_id "antmicropower:+1V1")
		(at 291.465 118.11 0)
		(unit 1)
		(exclude_from_sim no)
		(in_bom yes)
		(on_board yes)
		(dnp no)
		(fields_autoplaced yes)
		(property "Reference" "#PWR0152"
			(at 291.465 121.92 0)
			(effects
				(font
					(size 1.27 1.27)
				)
				(hide yes)
			)
		)
		(property "Value" "+1V1"
			(at 291.465 113.03 0)
			(effects
				(font
					(size 1.27 1.27)
				)
			)
		)
		(property "Footprint" ""
			(at 291.465 118.11 0)
			(effects
				(font
					(size 1.27 1.27)
				)
				(hide yes)
			)
		)
		(property "Datasheet" ""
			(at 291.465 118.11 0)
			(effects
				(font
					(size 1.27 1.27)
				)
				(hide yes)
			)
		)
		(property "Description" ""
			(at 291.465 118.11 0)
			(effects
				(font
					(size 1.27 1.27)
				)
			)
		)
		(pin "1"
		)
		(instances
			(project ""
				(path ""
					(reference "#PWR0152")
					(unit 1)
				)
			)
		)
	)
	(symbol
		(lib_id "antmicropower:PWR_FLAG")
		(at 294.64 74.295 270)
		(unit 1)
		(exclude_from_sim no)
		(in_bom yes)
		(on_board yes)
		(dnp no)
		(property "Reference" "#FLG0105"
			(at 296.545 74.295 0)
			(effects
				(font
					(size 1.27 1.27)
				)
				(hide yes)
			)
		)
		(property "Value" "PWR_FLAG"
			(at 297.815 74.295 90)
			(effects
				(font
					(size 1.27 1.27)
				)
				(justify left)
			)
		)
		(property "Footprint" ""
			(at 294.64 74.295 0)
			(effects
				(font
					(size 1.27 1.27)
				)
				(hide yes)
			)
		)
		(property "Datasheet" ""
			(at 294.64 74.295 0)
			(effects
				(font
					(size 1.27 1.27)
				)
				(hide yes)
			)
		)
		(property "Description" ""
			(at 294.64 74.295 0)
			(effects
				(font
					(size 1.27 1.27)
				)
			)
		)
		(pin "1"
		)
		(instances
			(project ""
				(path ""
					(reference "#FLG0105")
					(unit 1)
				)
			)
		)
	)
	(symbol
		(lib_id "antmicropower:GND")
		(at 180.975 80.01 0)
		(unit 1)
		(exclude_from_sim no)
		(in_bom yes)
		(on_board yes)
		(dnp no)
		(fields_autoplaced yes)
		(property "Reference" "#PWR0216"
			(at 189.865 82.55 0)
			(effects
				(font
					(size 1.27 1.27)
					(thickness 0.15)
				)
				(justify left bottom)
				(hide yes)
			)
		)
		(property "Value" "GND"
			(at 180.975 84.455 0)
			(effects
				(font
					(size 1.27 1.27)
					(thickness 0.15)
				)
			)
		)
		(property "Footprint" ""
			(at 189.865 87.63 0)
			(effects
				(font
					(size 1.27 1.27)
					(thickness 0.15)
				)
				(justify left bottom)
				(hide yes)
			)
		)
		(property "Datasheet" ""
			(at 189.865 92.71 0)
			(effects
				(font
					(size 1.27 1.27)
					(thickness 0.15)
				)
				(justify left bottom)
				(hide yes)
			)
		)
		(property "Description" ""
			(at 180.975 80.01 0)
			(effects
				(font
					(size 1.27 1.27)
				)
			)
		)
		(property "Author" "Antmicro"
			(at 189.865 87.63 0)
			(effects
				(font
					(size 1.27 1.27)
					(thickness 0.15)
				)
				(justify left bottom)
				(hide yes)
			)
		)
		(property "License" "Apache-2.0"
			(at 189.865 90.17 0)
			(effects
				(font
					(size 1.27 1.27)
					(thickness 0.15)
				)
				(justify left bottom)
				(hide yes)
			)
		)
		(pin "1"
		)
		(instances
			(project ""
				(path ""
					(reference "#PWR0216")
					(unit 1)
				)
			)
		)
	)
	(symbol
		(lib_id "antmicroResistors0603:R_0R_22.4A_0603")
		(at 332.74 178.435 0)
		(mirror y)
		(unit 1)
		(exclude_from_sim no)
		(in_bom yes)
		(on_board yes)
		(dnp no)
		(property "Reference" "R52"
			(at 332.74 177.165 0)
			(effects
				(font
					(size 1.27 1.27)
					(thickness 0.15)
				)
				(justify right)
			)
		)
		(property "Value" "R_0R_22.4A_0603"
			(at 330.2 169.545 0)
			(effects
				(font
					(size 1.27 1.27)
					(thickness 0.15)
				)
				(hide yes)
			)
		)
		(property "Footprint" "antmicro-footprints:R_0603_1608Metric"
			(at 317.5 188.595 0)
			(effects
				(font
					(size 1.27 1.27)
					(thickness 0.15)
				)
				(justify left bottom)
				(hide yes)
			)
		)
		(property "Datasheet" "https://fscdn.rohm.com/en/products/databook/datasheet/passive/resistor/chip_resistor/pmr-jpw-e.pdf"
			(at 317.5 191.135 0)
			(effects
				(font
					(size 1.27 1.27)
					(thickness 0.15)
				)
				(justify left bottom)
				(hide yes)
			)
		)
		(property "Description" ""
			(at 332.74 178.435 0)
			(effects
				(font
					(size 1.27 1.27)
				)
			)
		)
		(property "MPN" "PMR03EZPJ000"
			(at 317.5 193.675 0)
			(effects
				(font
					(size 1.27 1.27)
					(thickness 0.15)
				)
				(justify left bottom)
				(hide yes)
			)
		)
		(property "Manufacturer" "ROHM Semiconductor"
			(at 317.5 196.215 0)
			(effects
				(font
					(size 1.27 1.27)
					(thickness 0.15)
				)
				(justify left bottom)
				(hide yes)
			)
		)
		(property "Val" "0R"
			(at 326.39 177.165 0)
			(effects
				(font
					(size 1.27 1.27)
					(thickness 0.15)
				)
			)
		)
		(property "Max. Curr." "22.4A"
			(at 330.2 180.975 0)
			(effects
				(font
					(size 1.27 1.27)
					(thickness 0.15)
				)
			)
		)
		(property "Author" "Antmicro"
			(at 317.5 201.295 0)
			(effects
				(font
					(size 1.27 1.27)
					(thickness 0.15)
				)
				(justify left bottom)
				(hide yes)
			)
		)
		(property "License" "Apache-2.0"
			(at 317.5 203.835 0)
			(effects
				(font
					(size 1.27 1.27)
					(thickness 0.15)
				)
				(justify left bottom)
				(hide yes)
			)
		)
		(property "Tolerance" "template_tolerance"
			(at 312.42 188.595 0)
			(effects
				(font
					(size 1.27 1.27)
				)
				(justify left bottom)
				(hide yes)
			)
		)
		(pin "1"
		)
		(pin "2"
		)
		(instances
			(project ""
				(path ""
					(reference "R52")
					(unit 1)
				)
			)
		)
	)
	(symbol
		(lib_id "antmicropower:GND")
		(at 142.875 106.045 0)
		(unit 1)
		(exclude_from_sim no)
		(in_bom yes)
		(on_board yes)
		(dnp no)
		(fields_autoplaced yes)
		(property "Reference" "#PWR0222"
			(at 151.765 108.585 0)
			(effects
				(font
					(size 1.27 1.27)
					(thickness 0.15)
				)
				(justify left bottom)
				(hide yes)
			)
		)
		(property "Value" "GND"
			(at 142.875 110.49 0)
			(effects
				(font
					(size 1.27 1.27)
					(thickness 0.15)
				)
			)
		)
		(property "Footprint" ""
			(at 151.765 113.665 0)
			(effects
				(font
					(size 1.27 1.27)
					(thickness 0.15)
				)
				(justify left bottom)
				(hide yes)
			)
		)
		(property "Datasheet" ""
			(at 151.765 118.745 0)
			(effects
				(font
					(size 1.27 1.27)
					(thickness 0.15)
				)
				(justify left bottom)
				(hide yes)
			)
		)
		(property "Description" ""
			(at 142.875 106.045 0)
			(effects
				(font
					(size 1.27 1.27)
				)
			)
		)
		(property "Author" "Antmicro"
			(at 151.765 113.665 0)
			(effects
				(font
					(size 1.27 1.27)
					(thickness 0.15)
				)
				(justify left bottom)
				(hide yes)
			)
		)
		(property "License" "Apache-2.0"
			(at 151.765 116.205 0)
			(effects
				(font
					(size 1.27 1.27)
					(thickness 0.15)
				)
				(justify left bottom)
				(hide yes)
			)
		)
		(pin "1"
		)
		(instances
			(project ""
				(path ""
					(reference "#PWR0222")
					(unit 1)
				)
			)
		)
	)
	(symbol
		(lib_id "antmicroTransistorsFETsMOSFETsSingle:DMG1012T-7")
		(at 237.49 214.63 0)
		(unit 1)
		(exclude_from_sim no)
		(in_bom yes)
		(on_board yes)
		(dnp no)
		(fields_autoplaced yes)
		(property "Reference" "Q2"
			(at 247.65 210.8199 0)
			(effects
				(font
					(size 1.27 1.27)
					(thickness 0.15)
				)
				(justify left)
			)
		)
		(property "Value" "DMG1012T-7"
			(at 247.65 218.44 0)
			(effects
				(font
					(size 1.27 1.27)
					(thickness 0.15)
				)
				(justify left bottom)
				(hide yes)
			)
		)
		(property "Footprint" "antmicro-footprints:SOT-523"
			(at 247.65 220.98 0)
			(effects
				(font
					(size 1.27 1.27)
					(thickness 0.15)
				)
				(justify left bottom)
				(hide yes)
			)
		)
		(property "Datasheet" "https://www.diodes.com/assets/Datasheets/ds31783.pdf"
			(at 247.65 223.52 0)
			(effects
				(font
					(size 1.27 1.27)
					(thickness 0.15)
				)
				(justify left bottom)
				(hide yes)
			)
		)
		(property "Description" ""
			(at 237.49 214.63 0)
			(effects
				(font
					(size 1.27 1.27)
				)
			)
		)
		(property "MPN" "DMG1012T-7"
			(at 247.65 213.3599 0)
			(effects
				(font
					(size 1.27 1.27)
					(thickness 0.15)
				)
				(justify left)
			)
		)
		(property "Manufacturer" "Diodes Incorporated"
			(at 247.65 215.9 0)
			(effects
				(font
					(size 1.27 1.27)
					(thickness 0.15)
				)
				(justify left bottom)
				(hide yes)
			)
		)
		(property "Author" "Antmicro"
			(at 247.65 226.06 0)
			(effects
				(font
					(size 1.27 1.27)
					(thickness 0.15)
				)
				(justify left bottom)
				(hide yes)
			)
		)
		(property "License" "Apache-2.0"
			(at 247.65 228.6 0)
			(effects
				(font
					(size 1.27 1.27)
					(thickness 0.15)
				)
				(justify left bottom)
				(hide yes)
			)
		)
		(pin "1"
		)
		(pin "2"
		)
		(pin "3"
		)
		(instances
			(project ""
				(path ""
					(reference "Q2")
					(unit 1)
				)
			)
		)
	)
	(symbol
		(lib_id "antmicroResistors0603:R_0R_22.4A_0603")
		(at 285.115 104.14 0)
		(mirror y)
		(unit 1)
		(exclude_from_sim no)
		(in_bom yes)
		(on_board yes)
		(dnp no)
		(property "Reference" "R45"
			(at 285.115 102.87 0)
			(effects
				(font
					(size 1.27 1.27)
					(thickness 0.15)
				)
				(justify right)
			)
		)
		(property "Value" "R_0R_22.4A_0603"
			(at 282.575 95.25 0)
			(effects
				(font
					(size 1.27 1.27)
					(thickness 0.15)
				)
				(hide yes)
			)
		)
		(property "Footprint" "antmicro-footprints:R_0603_1608Metric"
			(at 269.875 114.3 0)
			(effects
				(font
					(size 1.27 1.27)
					(thickness 0.15)
				)
				(justify left bottom)
				(hide yes)
			)
		)
		(property "Datasheet" "https://fscdn.rohm.com/en/products/databook/datasheet/passive/resistor/chip_resistor/pmr-jpw-e.pdf"
			(at 269.875 116.84 0)
			(effects
				(font
					(size 1.27 1.27)
					(thickness 0.15)
				)
				(justify left bottom)
				(hide yes)
			)
		)
		(property "Description" ""
			(at 285.115 104.14 0)
			(effects
				(font
					(size 1.27 1.27)
				)
			)
		)
		(property "MPN" "PMR03EZPJ000"
			(at 269.875 119.38 0)
			(effects
				(font
					(size 1.27 1.27)
					(thickness 0.15)
				)
				(justify left bottom)
				(hide yes)
			)
		)
		(property "Manufacturer" "ROHM Semiconductor"
			(at 269.875 121.92 0)
			(effects
				(font
					(size 1.27 1.27)
					(thickness 0.15)
				)
				(justify left bottom)
				(hide yes)
			)
		)
		(property "Val" "0R"
			(at 278.765 102.87 0)
			(effects
				(font
					(size 1.27 1.27)
					(thickness 0.15)
				)
			)
		)
		(property "Max. Curr." "22.4A"
			(at 282.575 106.68 0)
			(effects
				(font
					(size 1.27 1.27)
					(thickness 0.15)
				)
			)
		)
		(property "Author" "Antmicro"
			(at 269.875 127 0)
			(effects
				(font
					(size 1.27 1.27)
					(thickness 0.15)
				)
				(justify left bottom)
				(hide yes)
			)
		)
		(property "License" "Apache-2.0"
			(at 269.875 129.54 0)
			(effects
				(font
					(size 1.27 1.27)
					(thickness 0.15)
				)
				(justify left bottom)
				(hide yes)
			)
		)
		(property "Tolerance" "template_tolerance"
			(at 264.795 114.3 0)
			(effects
				(font
					(size 1.27 1.27)
				)
				(justify left bottom)
				(hide yes)
			)
		)
		(pin "1"
		)
		(pin "2"
		)
		(instances
			(project ""
				(path ""
					(reference "R45")
					(unit 1)
				)
			)
		)
	)
	(symbol
		(lib_id "antmicroTrimmerPotentiometers:TC33X-2-203E")
		(at 281.305 197.485 90)
		(unit 1)
		(exclude_from_sim no)
		(in_bom yes)
		(on_board yes)
		(dnp no)
		(fields_autoplaced yes)
		(property "Reference" "POT1"
			(at 283.845 192.4049 90)
			(effects
				(font
					(size 1.27 1.27)
					(thickness 0.15)
				)
				(justify right)
			)
		)
		(property "Value" "TC33X-2-203E"
			(at 283.845 194.9449 90)
			(effects
				(font
					(size 1.27 1.27)
					(thickness 0.15)
				)
				(justify right)
			)
		)
		(property "Footprint" "antmicro-footprints:Trimpot_3.8mmx3.6mm_TC33X-2-103E"
			(at 286.385 182.245 0)
			(effects
				(font
					(size 1.27 1.27)
					(thickness 0.15)
				)
				(justify left bottom)
				(hide yes)
			)
		)
		(property "Datasheet" "https://www.bourns.com/docs/Product-Datasheets/TC33.pdf"
			(at 288.925 182.245 0)
			(effects
				(font
					(size 1.27 1.27)
					(thickness 0.15)
				)
				(justify left bottom)
				(hide yes)
			)
		)
		(property "Description" ""
			(at 281.305 197.485 0)
			(effects
				(font
					(size 1.27 1.27)
				)
			)
		)
		(property "MPN" "TC33X-2-203E"
			(at 291.465 182.245 0)
			(effects
				(font
					(size 1.27 1.27)
					(thickness 0.15)
				)
				(justify left bottom)
				(hide yes)
			)
		)
		(property "Manufacturer" "Bourns"
			(at 294.005 182.245 0)
			(effects
				(font
					(size 1.27 1.27)
					(thickness 0.15)
				)
				(justify left bottom)
				(hide yes)
			)
		)
		(property "Author" "Antmicro"
			(at 296.545 182.245 0)
			(effects
				(font
					(size 1.27 1.27)
					(thickness 0.15)
				)
				(justify left bottom)
				(hide yes)
			)
		)
		(property "License" "Apache-2.0"
			(at 299.085 182.245 0)
			(effects
				(font
					(size 1.27 1.27)
					(thickness 0.15)
				)
				(justify left bottom)
				(hide yes)
			)
		)
		(pin "1"
		)
		(pin "2"
		)
		(pin "3"
		)
		(instances
			(project ""
				(path ""
					(reference "POT1")
					(unit 1)
				)
			)
		)
	)
	(symbol
		(lib_id "antmicroCapacitors0603:C_22u_0603")
		(at 266.7 125.73 90)
		(unit 1)
		(exclude_from_sim no)
		(in_bom yes)
		(on_board yes)
		(dnp no)
		(property "Reference" "C19"
			(at 267.335 121.285 90)
			(effects
				(font
					(size 1.27 1.27)
					(thickness 0.15)
				)
				(justify right)
			)
		)
		(property "Value" "C_22u_0603"
			(at 276.86 105.41 0)
			(effects
				(font
					(size 1.27 1.27)
					(thickness 0.15)
				)
				(justify left bottom)
				(hide yes)
			)
		)
		(property "Footprint" "antmicro-footprints:C_0603_1608Metric"
			(at 279.4 105.41 0)
			(effects
				(font
					(size 1.27 1.27)
					(thickness 0.15)
				)
				(justify left bottom)
				(hide yes)
			)
		)
		(property "Datasheet" "https://www.murata.com/products/productdetail?partno=GRM188R60J226MEA0%23"
			(at 281.94 105.41 0)
			(effects
				(font
					(size 1.27 1.27)
					(thickness 0.15)
				)
				(justify left bottom)
				(hide yes)
			)
		)
		(property "Description" ""
			(at 266.7 125.73 0)
			(effects
				(font
					(size 1.27 1.27)
				)
			)
		)
		(property "MPN" "GRM188R60J226MEA0D"
			(at 284.48 105.41 0)
			(effects
				(font
					(size 1.27 1.27)
					(thickness 0.15)
				)
				(justify left bottom)
				(hide yes)
			)
		)
		(property "Manufacturer" "Murata"
			(at 287.02 105.41 0)
			(effects
				(font
					(size 1.27 1.27)
					(thickness 0.15)
				)
				(justify left bottom)
				(hide yes)
			)
		)
		(property "License" "Apache-2.0"
			(at 289.56 105.41 0)
			(effects
				(font
					(size 1.27 1.27)
					(thickness 0.15)
				)
				(justify left bottom)
				(hide yes)
			)
		)
		(property "Author" "Antmicro"
			(at 292.1 105.41 0)
			(effects
				(font
					(size 1.27 1.27)
					(thickness 0.15)
				)
				(justify left bottom)
				(hide yes)
			)
		)
		(property "Val" "22u"
			(at 267.335 125.095 90)
			(effects
				(font
					(size 1.27 1.27)
					(thickness 0.15)
				)
				(justify right)
			)
		)
		(property "Voltage" ""
			(at 294.64 105.41 0)
			(effects
				(font
					(size 1.27 1.27)
				)
				(justify left bottom)
				(hide yes)
			)
		)
		(property "Dielectric" ""
			(at 297.18 105.41 0)
			(effects
				(font
					(size 1.27 1.27)
				)
				(justify left bottom)
				(hide yes)
			)
		)
		(pin "1"
		)
		(pin "2"
		)
		(instances
			(project ""
				(path ""
					(reference "C19")
					(unit 1)
				)
			)
		)
	)
	(symbol
		(lib_id "antmicropower:GND")
		(at 170.815 64.135 0)
		(unit 1)
		(exclude_from_sim no)
		(in_bom yes)
		(on_board yes)
		(dnp no)
		(property "Reference" "#PWR0218"
			(at 179.705 66.675 0)
			(effects
				(font
					(size 1.27 1.27)
					(thickness 0.15)
				)
				(justify left bottom)
				(hide yes)
			)
		)
		(property "Value" "GND"
			(at 170.815 67.945 0)
			(effects
				(font
					(size 1.27 1.27)
					(thickness 0.15)
				)
			)
		)
		(property "Footprint" ""
			(at 179.705 71.755 0)
			(effects
				(font
					(size 1.27 1.27)
					(thickness 0.15)
				)
				(justify left bottom)
				(hide yes)
			)
		)
		(property "Datasheet" ""
			(at 179.705 76.835 0)
			(effects
				(font
					(size 1.27 1.27)
					(thickness 0.15)
				)
				(justify left bottom)
				(hide yes)
			)
		)
		(property "Description" ""
			(at 170.815 64.135 0)
			(effects
				(font
					(size 1.27 1.27)
				)
			)
		)
		(property "Author" "Antmicro"
			(at 179.705 71.755 0)
			(effects
				(font
					(size 1.27 1.27)
					(thickness 0.15)
				)
				(justify left bottom)
				(hide yes)
			)
		)
		(property "License" "Apache-2.0"
			(at 179.705 74.295 0)
			(effects
				(font
					(size 1.27 1.27)
					(thickness 0.15)
				)
				(justify left bottom)
				(hide yes)
			)
		)
		(pin "1"
		)
		(instances
			(project ""
				(path ""
					(reference "#PWR0218")
					(unit 1)
				)
			)
		)
	)
	(symbol
		(lib_id "antmicropower:GND")
		(at 266.7 125.73 0)
		(unit 1)
		(exclude_from_sim no)
		(in_bom yes)
		(on_board yes)
		(dnp no)
		(fields_autoplaced yes)
		(property "Reference" "#PWR0213"
			(at 275.59 128.27 0)
			(effects
				(font
					(size 1.27 1.27)
					(thickness 0.15)
				)
				(justify left bottom)
				(hide yes)
			)
		)
		(property "Value" "GND"
			(at 266.7 130.175 0)
			(effects
				(font
					(size 1.27 1.27)
					(thickness 0.15)
				)
			)
		)
		(property "Footprint" ""
			(at 275.59 133.35 0)
			(effects
				(font
					(size 1.27 1.27)
					(thickness 0.15)
				)
				(justify left bottom)
				(hide yes)
			)
		)
		(property "Datasheet" ""
			(at 275.59 138.43 0)
			(effects
				(font
					(size 1.27 1.27)
					(thickness 0.15)
				)
				(justify left bottom)
				(hide yes)
			)
		)
		(property "Description" ""
			(at 266.7 125.73 0)
			(effects
				(font
					(size 1.27 1.27)
				)
			)
		)
		(property "Author" "Antmicro"
			(at 275.59 133.35 0)
			(effects
				(font
					(size 1.27 1.27)
					(thickness 0.15)
				)
				(justify left bottom)
				(hide yes)
			)
		)
		(property "License" "Apache-2.0"
			(at 275.59 135.89 0)
			(effects
				(font
					(size 1.27 1.27)
					(thickness 0.15)
				)
				(justify left bottom)
				(hide yes)
			)
		)
		(pin "1"
		)
		(instances
			(project ""
				(path ""
					(reference "#PWR0213")
					(unit 1)
				)
			)
		)
	)
	(symbol
		(lib_id "antmicroResistors0402:R_25k5_0402")
		(at 189.23 196.215 90)
		(unit 1)
		(exclude_from_sim no)
		(in_bom yes)
		(on_board yes)
		(dnp no)
		(property "Reference" "R32"
			(at 190.5 192.405 90)
			(effects
				(font
					(size 1.27 1.27)
					(thickness 0.15)
				)
				(justify right)
			)
		)
		(property "Value" "R_25k5_0402"
			(at 201.93 175.895 0)
			(effects
				(font
					(size 1.27 1.27)
					(thickness 0.15)
				)
				(justify left bottom)
				(hide yes)
			)
		)
		(property "Footprint" "antmicro-footprints:R_0402_1005Metric"
			(at 204.47 175.895 0)
			(effects
				(font
					(size 1.27 1.27)
					(thickness 0.15)
				)
				(justify left bottom)
				(hide yes)
			)
		)
		(property "Datasheet" "https://www.bourns.com/docs/product-datasheets/cr.pdf"
			(at 207.01 175.895 0)
			(effects
				(font
					(size 1.27 1.27)
					(thickness 0.15)
				)
				(justify left bottom)
				(hide yes)
			)
		)
		(property "Description" ""
			(at 189.23 196.215 0)
			(effects
				(font
					(size 1.27 1.27)
				)
			)
		)
		(property "MPN" "CR0402-FX-2552GLF"
			(at 209.55 175.895 0)
			(effects
				(font
					(size 1.27 1.27)
					(thickness 0.15)
				)
				(justify left bottom)
				(hide yes)
			)
		)
		(property "Manufacturer" "Bourns"
			(at 212.09 175.895 0)
			(effects
				(font
					(size 1.27 1.27)
					(thickness 0.15)
				)
				(justify left bottom)
				(hide yes)
			)
		)
		(property "License" "Apache-2.0"
			(at 214.63 175.895 0)
			(effects
				(font
					(size 1.27 1.27)
					(thickness 0.15)
				)
				(justify left bottom)
				(hide yes)
			)
		)
		(property "Author" "Antmicro"
			(at 217.17 175.895 0)
			(effects
				(font
					(size 1.27 1.27)
					(thickness 0.15)
				)
				(justify left bottom)
				(hide yes)
			)
		)
		(property "Val" "25k5"
			(at 190.5 194.945 90)
			(effects
				(font
					(size 1.27 1.27)
					(thickness 0.15)
				)
				(justify right)
			)
		)
		(property "Tolerance" "1%"
			(at 199.39 175.895 0)
			(effects
				(font
					(size 1.27 1.27)
				)
				(justify left bottom)
				(hide yes)
			)
		)
		(pin "1"
		)
		(pin "2"
		)
		(instances
			(project ""
				(path ""
					(reference "R32")
					(unit 1)
				)
			)
		)
	)
	(symbol
		(lib_id "antmicroTVSDiodes:PTVS48VS1UR,115")
		(at 159.385 81.28 90)
		(unit 1)
		(exclude_from_sim no)
		(in_bom yes)
		(on_board yes)
		(dnp no)
		(property "Reference" "D1"
			(at 160.02 74.295 90)
			(effects
				(font
					(size 1.27 1.27)
					(thickness 0.15)
				)
				(justify right)
			)
		)
		(property "Value" "PTVS48VS1UR"
			(at 160.02 80.645 90)
			(effects
				(font
					(size 1.27 1.27)
					(thickness 0.15)
				)
				(justify right)
			)
		)
		(property "Footprint" "antmicro-footprints:D_SOD-123F"
			(at 169.545 59.69 0)
			(effects
				(font
					(size 1.27 1.27)
					(thickness 0.15)
				)
				(justify left bottom)
				(hide yes)
			)
		)
		(property "Datasheet" "https://www.mouser.com/datasheet/2/916/PTVSXS1UR_SER-1545507.pdf"
			(at 172.085 59.69 0)
			(effects
				(font
					(size 1.27 1.27)
					(thickness 0.15)
				)
				(justify left bottom)
				(hide yes)
			)
		)
		(property "Description" ""
			(at 159.385 81.28 0)
			(effects
				(font
					(size 1.27 1.27)
				)
			)
		)
		(property "MPN" "PTVS48VS1UR,115"
			(at 174.625 59.69 0)
			(effects
				(font
					(size 1.27 1.27)
					(thickness 0.15)
				)
				(justify left bottom)
				(hide yes)
			)
		)
		(property "Manufacturer" "Nexperia"
			(at 177.165 59.69 0)
			(effects
				(font
					(size 1.27 1.27)
					(thickness 0.15)
				)
				(justify left bottom)
				(hide yes)
			)
		)
		(property "Author" "Antmicro"
			(at 179.705 59.69 0)
			(effects
				(font
					(size 1.27 1.27)
					(thickness 0.15)
				)
				(justify left bottom)
				(hide yes)
			)
		)
		(property "License" "Apache-2.0"
			(at 182.245 59.69 0)
			(effects
				(font
					(size 1.27 1.27)
					(thickness 0.15)
				)
				(justify left bottom)
				(hide yes)
			)
		)
		(pin "A"
		)
		(pin "K"
		)
		(instances
			(project ""
				(path ""
					(reference "D1")
					(unit 1)
				)
			)
		)
	)
	(symbol
		(lib_id "antmicroResistors0402:R_100k_0402")
		(at 236.22 83.82 0)
		(unit 1)
		(exclude_from_sim no)
		(in_bom yes)
		(on_board yes)
		(dnp no)
		(property "Reference" "R33"
			(at 234.315 82.55 0)
			(effects
				(font
					(size 1.27 1.27)
					(thickness 0.15)
				)
			)
		)
		(property "Value" "R_100k_0402"
			(at 256.54 96.52 0)
			(effects
				(font
					(size 1.27 1.27)
					(thickness 0.15)
				)
				(justify left bottom)
				(hide yes)
			)
		)
		(property "Footprint" "antmicro-footprints:R_0402_1005Metric"
			(at 256.54 99.06 0)
			(effects
				(font
					(size 1.27 1.27)
					(thickness 0.15)
				)
				(justify left bottom)
				(hide yes)
			)
		)
		(property "Datasheet" "https://www.bourns.com/docs/product-datasheets/cr.pdf"
			(at 256.54 101.6 0)
			(effects
				(font
					(size 1.27 1.27)
					(thickness 0.15)
				)
				(justify left bottom)
				(hide yes)
			)
		)
		(property "Description" ""
			(at 236.22 83.82 0)
			(effects
				(font
					(size 1.27 1.27)
				)
			)
		)
		(property "MPN" "CR0402-FX-1003GLF"
			(at 256.54 104.14 0)
			(effects
				(font
					(size 1.27 1.27)
					(thickness 0.15)
				)
				(justify left bottom)
				(hide yes)
			)
		)
		(property "Manufacturer" "Bourns"
			(at 256.54 106.68 0)
			(effects
				(font
					(size 1.27 1.27)
					(thickness 0.15)
				)
				(justify left bottom)
				(hide yes)
			)
		)
		(property "License" "Apache-2.0"
			(at 256.54 109.22 0)
			(effects
				(font
					(size 1.27 1.27)
					(thickness 0.15)
				)
				(justify left bottom)
				(hide yes)
			)
		)
		(property "Author" "Antmicro"
			(at 256.54 111.76 0)
			(effects
				(font
					(size 1.27 1.27)
					(thickness 0.15)
				)
				(justify left bottom)
				(hide yes)
			)
		)
		(property "Val" "100k"
			(at 243.205 82.55 0)
			(effects
				(font
					(size 1.27 1.27)
					(thickness 0.15)
				)
			)
		)
		(property "Tolerance" "1%"
			(at 256.54 93.98 0)
			(effects
				(font
					(size 1.27 1.27)
				)
				(justify left bottom)
				(hide yes)
			)
		)
		(pin "1"
		)
		(pin "2"
		)
		(instances
			(project ""
				(path ""
					(reference "R33")
					(unit 1)
				)
			)
		)
	)
	(symbol
		(lib_id "antmicroCapacitors0603:C_22u_0603")
		(at 266.7 110.49 90)
		(unit 1)
		(exclude_from_sim no)
		(in_bom yes)
		(on_board yes)
		(dnp no)
		(property "Reference" "C18"
			(at 267.335 106.045 90)
			(effects
				(font
					(size 1.27 1.27)
					(thickness 0.15)
				)
				(justify right)
			)
		)
		(property "Value" "C_22u_0603"
			(at 276.86 90.17 0)
			(effects
				(font
					(size 1.27 1.27)
					(thickness 0.15)
				)
				(justify left bottom)
				(hide yes)
			)
		)
		(property "Footprint" "antmicro-footprints:C_0603_1608Metric"
			(at 279.4 90.17 0)
			(effects
				(font
					(size 1.27 1.27)
					(thickness 0.15)
				)
				(justify left bottom)
				(hide yes)
			)
		)
		(property "Datasheet" "https://www.murata.com/products/productdetail?partno=GRM188R60J226MEA0%23"
			(at 281.94 90.17 0)
			(effects
				(font
					(size 1.27 1.27)
					(thickness 0.15)
				)
				(justify left bottom)
				(hide yes)
			)
		)
		(property "Description" ""
			(at 266.7 110.49 0)
			(effects
				(font
					(size 1.27 1.27)
				)
			)
		)
		(property "MPN" "GRM188R60J226MEA0D"
			(at 284.48 90.17 0)
			(effects
				(font
					(size 1.27 1.27)
					(thickness 0.15)
				)
				(justify left bottom)
				(hide yes)
			)
		)
		(property "Manufacturer" "Murata"
			(at 287.02 90.17 0)
			(effects
				(font
					(size 1.27 1.27)
					(thickness 0.15)
				)
				(justify left bottom)
				(hide yes)
			)
		)
		(property "License" "Apache-2.0"
			(at 289.56 90.17 0)
			(effects
				(font
					(size 1.27 1.27)
					(thickness 0.15)
				)
				(justify left bottom)
				(hide yes)
			)
		)
		(property "Author" "Antmicro"
			(at 292.1 90.17 0)
			(effects
				(font
					(size 1.27 1.27)
					(thickness 0.15)
				)
				(justify left bottom)
				(hide yes)
			)
		)
		(property "Val" "22u"
			(at 267.335 109.855 90)
			(effects
				(font
					(size 1.27 1.27)
					(thickness 0.15)
				)
				(justify right)
			)
		)
		(property "Voltage" ""
			(at 294.64 90.17 0)
			(effects
				(font
					(size 1.27 1.27)
				)
				(justify left bottom)
				(hide yes)
			)
		)
		(property "Dielectric" ""
			(at 297.18 90.17 0)
			(effects
				(font
					(size 1.27 1.27)
				)
				(justify left bottom)
				(hide yes)
			)
		)
		(pin "1"
		)
		(pin "2"
		)
		(instances
			(project ""
				(path ""
					(reference "C18")
					(unit 1)
				)
			)
		)
	)
	(symbol
		(lib_id "antmicroCapacitors0603:C_22u_0603")
		(at 257.81 80.645 90)
		(unit 1)
		(exclude_from_sim no)
		(in_bom yes)
		(on_board yes)
		(dnp no)
		(property "Reference" "C14"
			(at 258.445 76.2 90)
			(effects
				(font
					(size 1.27 1.27)
					(thickness 0.15)
				)
				(justify right)
			)
		)
		(property "Value" "C_22u_0603"
			(at 267.97 60.325 0)
			(effects
				(font
					(size 1.27 1.27)
					(thickness 0.15)
				)
				(justify left bottom)
				(hide yes)
			)
		)
		(property "Footprint" "antmicro-footprints:C_0603_1608Metric"
			(at 270.51 60.325 0)
			(effects
				(font
					(size 1.27 1.27)
					(thickness 0.15)
				)
				(justify left bottom)
				(hide yes)
			)
		)
		(property "Datasheet" "https://www.murata.com/products/productdetail?partno=GRM188R60J226MEA0%23"
			(at 273.05 60.325 0)
			(effects
				(font
					(size 1.27 1.27)
					(thickness 0.15)
				)
				(justify left bottom)
				(hide yes)
			)
		)
		(property "Description" ""
			(at 257.81 80.645 0)
			(effects
				(font
					(size 1.27 1.27)
				)
			)
		)
		(property "MPN" "GRM188R60J226MEA0D"
			(at 275.59 60.325 0)
			(effects
				(font
					(size 1.27 1.27)
					(thickness 0.15)
				)
				(justify left bottom)
				(hide yes)
			)
		)
		(property "Manufacturer" "Murata"
			(at 278.13 60.325 0)
			(effects
				(font
					(size 1.27 1.27)
					(thickness 0.15)
				)
				(justify left bottom)
				(hide yes)
			)
		)
		(property "License" "Apache-2.0"
			(at 280.67 60.325 0)
			(effects
				(font
					(size 1.27 1.27)
					(thickness 0.15)
				)
				(justify left bottom)
				(hide yes)
			)
		)
		(property "Author" "Antmicro"
			(at 283.21 60.325 0)
			(effects
				(font
					(size 1.27 1.27)
					(thickness 0.15)
				)
				(justify left bottom)
				(hide yes)
			)
		)
		(property "Val" "22u"
			(at 258.445 80.01 90)
			(effects
				(font
					(size 1.27 1.27)
					(thickness 0.15)
				)
				(justify right)
			)
		)
		(property "Voltage" ""
			(at 285.75 60.325 0)
			(effects
				(font
					(size 1.27 1.27)
				)
				(justify left bottom)
				(hide yes)
			)
		)
		(property "Dielectric" ""
			(at 288.29 60.325 0)
			(effects
				(font
					(size 1.27 1.27)
				)
				(justify left bottom)
				(hide yes)
			)
		)
		(pin "1"
		)
		(pin "2"
		)
		(instances
			(project ""
				(path ""
					(reference "C14")
					(unit 1)
				)
			)
		)
	)
	(symbol
		(lib_id "antmicroCapacitors0402:C_1u_0402")
		(at 180.975 80.01 90)
		(unit 1)
		(exclude_from_sim no)
		(in_bom yes)
		(on_board yes)
		(dnp no)
		(property "Reference" "C12"
			(at 181.61 75.565 90)
			(effects
				(font
					(size 1.27 1.27)
					(thickness 0.15)
				)
				(justify right)
			)
		)
		(property "Value" "C_1u_0402"
			(at 191.135 59.69 0)
			(effects
				(font
					(size 1.27 1.27)
					(thickness 0.15)
				)
				(justify left bottom)
				(hide yes)
			)
		)
		(property "Footprint" "antmicro-footprints:C_0402_1005Metric"
			(at 193.675 59.69 0)
			(effects
				(font
					(size 1.27 1.27)
					(thickness 0.15)
				)
				(justify left bottom)
				(hide yes)
			)
		)
		(property "Datasheet" "https://product.tdk.com/en/search/capacitor/ceramic/mlcc/info?part_no=C1005X6S1A105K050BC"
			(at 196.215 59.69 0)
			(effects
				(font
					(size 1.27 1.27)
					(thickness 0.15)
				)
				(justify left bottom)
				(hide yes)
			)
		)
		(property "Description" ""
			(at 180.975 80.01 0)
			(effects
				(font
					(size 1.27 1.27)
				)
			)
		)
		(property "MPN" "C1005X6S1A105K050BC"
			(at 198.755 59.69 0)
			(effects
				(font
					(size 1.27 1.27)
					(thickness 0.15)
				)
				(justify left bottom)
				(hide yes)
			)
		)
		(property "Manufacturer" "TDK"
			(at 201.295 59.69 0)
			(effects
				(font
					(size 1.27 1.27)
					(thickness 0.15)
				)
				(justify left bottom)
				(hide yes)
			)
		)
		(property "License" "Apache-2.0"
			(at 203.835 59.69 0)
			(effects
				(font
					(size 1.27 1.27)
					(thickness 0.15)
				)
				(justify left bottom)
				(hide yes)
			)
		)
		(property "Author" "Antmicro"
			(at 206.375 59.69 0)
			(effects
				(font
					(size 1.27 1.27)
					(thickness 0.15)
				)
				(justify left bottom)
				(hide yes)
			)
		)
		(property "Val" "1u"
			(at 181.61 79.375 90)
			(effects
				(font
					(size 1.27 1.27)
					(thickness 0.15)
				)
				(justify right)
			)
		)
		(property "Voltage" ""
			(at 208.915 59.69 0)
			(effects
				(font
					(size 1.27 1.27)
				)
				(justify left bottom)
				(hide yes)
			)
		)
		(property "Dielectric" ""
			(at 211.455 59.69 0)
			(effects
				(font
					(size 1.27 1.27)
				)
				(justify left bottom)
				(hide yes)
			)
		)
		(pin "1"
		)
		(pin "2"
		)
		(instances
			(project ""
				(path ""
					(reference "C12")
					(unit 1)
				)
			)
		)
	)
	(symbol
		(lib_id "antmicroWire2BoardConnectors:JST_SH_1x4_SM04B-SRSS-TB-LF-SN")
		(at 141.605 92.71 0)
		(mirror y)
		(unit 1)
		(exclude_from_sim no)
		(in_bom yes)
		(on_board yes)
		(dnp no)
		(property "Reference" "J3"
			(at 136.525 89.535 0)
			(effects
				(font
					(size 1.27 1.27)
					(thickness 0.15)
				)
			)
		)
		(property "Value" "JST_SH_1x4_SM04B-SRSS-TB-LF-SN"
			(at 114.935 100.33 0)
			(effects
				(font
					(size 1.27 1.27)
					(thickness 0.15)
				)
				(justify left bottom)
				(hide yes)
			)
		)
		(property "Footprint" "antmicro-footprints:Conn_JST_SH_1x4_SM04B-SRSS-TB-LF-SN"
			(at 114.935 102.87 0)
			(effects
				(font
					(size 1.27 1.27)
					(thickness 0.15)
				)
				(justify left bottom)
				(hide yes)
			)
		)
		(property "Datasheet" "https://www.jst-mfg.com/product/pdf/eng/eSH.pdf"
			(at 114.935 105.41 0)
			(effects
				(font
					(size 1.27 1.27)
					(thickness 0.15)
				)
				(justify left bottom)
				(hide yes)
			)
		)
		(property "Description" ""
			(at 141.605 92.71 0)
			(effects
				(font
					(size 1.27 1.27)
				)
			)
		)
		(property "MPN" "SM04B-SRSS-TB(LF)(SN)"
			(at 132.715 100.33 90)
			(effects
				(font
					(size 1.27 1.27)
					(thickness 0.15)
				)
			)
		)
		(property "Manufacturer" "JST Automotive Connectors"
			(at 114.935 107.95 0)
			(effects
				(font
					(size 1.27 1.27)
					(thickness 0.15)
				)
				(justify left bottom)
				(hide yes)
			)
		)
		(property "Author" "Antmicro"
			(at 114.935 110.49 0)
			(effects
				(font
					(size 1.27 1.27)
					(thickness 0.15)
				)
				(justify left bottom)
				(hide yes)
			)
		)
		(property "License" "Apache-2.0"
			(at 114.935 113.03 0)
			(effects
				(font
					(size 1.27 1.27)
					(thickness 0.15)
				)
				(justify left bottom)
				(hide yes)
			)
		)
		(pin "1"
		)
		(pin "2"
		)
		(pin "3"
		)
		(pin "4"
		)
		(pin "SH1"
		)
		(pin "SH2"
		)
		(instances
			(project ""
				(path ""
					(reference "J3")
					(unit 1)
				)
			)
		)
	)
	(symbol
		(lib_id "antmicroResistors0402:R_200k_0402")
		(at 236.22 99.06 0)
		(unit 1)
		(exclude_from_sim no)
		(in_bom yes)
		(on_board yes)
		(dnp no)
		(property "Reference" "R36"
			(at 234.315 97.79 0)
			(effects
				(font
					(size 1.27 1.27)
					(thickness 0.15)
				)
			)
		)
		(property "Value" "R_200k_0402"
			(at 256.54 111.76 0)
			(effects
				(font
					(size 1.27 1.27)
					(thickness 0.15)
				)
				(justify left bottom)
				(hide yes)
			)
		)
		(property "Footprint" "antmicro-footprints:R_0402_1005Metric"
			(at 256.54 114.3 0)
			(effects
				(font
					(size 1.27 1.27)
					(thickness 0.15)
				)
				(justify left bottom)
				(hide yes)
			)
		)
		(property "Datasheet" "https://www.bourns.com/docs/product-datasheets/cr.pdf"
			(at 256.54 116.84 0)
			(effects
				(font
					(size 1.27 1.27)
					(thickness 0.15)
				)
				(justify left bottom)
				(hide yes)
			)
		)
		(property "Description" ""
			(at 236.22 99.06 0)
			(effects
				(font
					(size 1.27 1.27)
				)
			)
		)
		(property "MPN" "CR0402-FX-2003GLF"
			(at 256.54 119.38 0)
			(effects
				(font
					(size 1.27 1.27)
					(thickness 0.15)
				)
				(justify left bottom)
				(hide yes)
			)
		)
		(property "Manufacturer" "Bourns"
			(at 256.54 121.92 0)
			(effects
				(font
					(size 1.27 1.27)
					(thickness 0.15)
				)
				(justify left bottom)
				(hide yes)
			)
		)
		(property "License" "Apache-2.0"
			(at 256.54 124.46 0)
			(effects
				(font
					(size 1.27 1.27)
					(thickness 0.15)
				)
				(justify left bottom)
				(hide yes)
			)
		)
		(property "Author" "Antmicro"
			(at 256.54 127 0)
			(effects
				(font
					(size 1.27 1.27)
					(thickness 0.15)
				)
				(justify left bottom)
				(hide yes)
			)
		)
		(property "Val" "200k"
			(at 243.205 97.79 0)
			(effects
				(font
					(size 1.27 1.27)
					(thickness 0.15)
				)
			)
		)
		(property "Tolerance" "1%"
			(at 256.54 109.22 0)
			(effects
				(font
					(size 1.27 1.27)
				)
				(justify left bottom)
				(hide yes)
			)
		)
		(pin "1"
		)
		(pin "2"
		)
		(instances
			(project ""
				(path ""
					(reference "R36")
					(unit 1)
				)
			)
		)
	)
	(symbol
		(lib_id "antmicroResistors0402:R_100k_0402")
		(at 236.22 104.14 0)
		(unit 1)
		(exclude_from_sim no)
		(in_bom yes)
		(on_board yes)
		(dnp no)
		(property "Reference" "R37"
			(at 234.95 102.87 0)
			(effects
				(font
					(size 1.27 1.27)
					(thickness 0.15)
				)
			)
		)
		(property "Value" "R_100k_0402"
			(at 256.54 116.84 0)
			(effects
				(font
					(size 1.27 1.27)
					(thickness 0.15)
				)
				(justify left bottom)
				(hide yes)
			)
		)
		(property "Footprint" "antmicro-footprints:R_0402_1005Metric"
			(at 256.54 119.38 0)
			(effects
				(font
					(size 1.27 1.27)
					(thickness 0.15)
				)
				(justify left bottom)
				(hide yes)
			)
		)
		(property "Datasheet" "https://www.bourns.com/docs/product-datasheets/cr.pdf"
			(at 256.54 121.92 0)
			(effects
				(font
					(size 1.27 1.27)
					(thickness 0.15)
				)
				(justify left bottom)
				(hide yes)
			)
		)
		(property "Description" ""
			(at 236.22 104.14 0)
			(effects
				(font
					(size 1.27 1.27)
				)
			)
		)
		(property "MPN" "CR0402-FX-1003GLF"
			(at 256.54 124.46 0)
			(effects
				(font
					(size 1.27 1.27)
					(thickness 0.15)
				)
				(justify left bottom)
				(hide yes)
			)
		)
		(property "Manufacturer" "Bourns"
			(at 256.54 127 0)
			(effects
				(font
					(size 1.27 1.27)
					(thickness 0.15)
				)
				(justify left bottom)
				(hide yes)
			)
		)
		(property "License" "Apache-2.0"
			(at 256.54 129.54 0)
			(effects
				(font
					(size 1.27 1.27)
					(thickness 0.15)
				)
				(justify left bottom)
				(hide yes)
			)
		)
		(property "Author" "Antmicro"
			(at 256.54 132.08 0)
			(effects
				(font
					(size 1.27 1.27)
					(thickness 0.15)
				)
				(justify left bottom)
				(hide yes)
			)
		)
		(property "Val" "100k"
			(at 243.205 102.87 0)
			(effects
				(font
					(size 1.27 1.27)
					(thickness 0.15)
				)
			)
		)
		(property "Tolerance" "1%"
			(at 256.54 114.3 0)
			(effects
				(font
					(size 1.27 1.27)
				)
				(justify left bottom)
				(hide yes)
			)
		)
		(pin "1"
		)
		(pin "2"
		)
		(instances
			(project ""
				(path ""
					(reference "R37")
					(unit 1)
				)
			)
		)
	)
	(symbol
		(lib_id "antmicroTestPoints:TP_0.75mm_SMD")
		(at 189.23 186.055 180)
		(unit 1)
		(exclude_from_sim no)
		(in_bom yes)
		(on_board yes)
		(dnp no)
		(property "Reference" "TP1"
			(at 185.42 188.595 0)
			(effects
				(font
					(size 1.27 1.27)
					(thickness 0.15)
				)
			)
		)
		(property "Value" "TP_0.75mm_SMD"
			(at 178.435 182.245 0)
			(effects
				(font
					(size 1.27 1.27)
					(thickness 0.15)
				)
				(justify left bottom)
				(hide yes)
			)
		)
		(property "Footprint" "antmicro-footprints:TP_SMD_0.75mm"
			(at 178.435 179.705 0)
			(effects
				(font
					(size 1.27 1.27)
					(thickness 0.15)
				)
				(justify left bottom)
				(hide yes)
			)
		)
		(property "Datasheet" ""
			(at 171.45 173.355 0)
			(effects
				(font
					(size 1.27 1.27)
					(thickness 0.15)
				)
				(justify left bottom)
				(hide yes)
			)
		)
		(property "Description" ""
			(at 189.23 186.055 0)
			(effects
				(font
					(size 1.27 1.27)
				)
			)
		)
		(property "MPN" ""
			(at 178.435 174.625 0)
			(effects
				(font
					(size 1.27 1.27)
					(thickness 0.15)
				)
				(justify left bottom)
				(hide yes)
			)
		)
		(property "Manufacturer" ""
			(at 178.435 179.705 0)
			(effects
				(font
					(size 1.27 1.27)
					(thickness 0.15)
				)
				(justify left bottom)
				(hide yes)
			)
		)
		(property "Author" "Antmicro"
			(at 178.435 177.165 0)
			(effects
				(font
					(size 1.27 1.27)
					(thickness 0.15)
				)
				(justify left bottom)
				(hide yes)
			)
		)
		(property "License" "Apache-2.0"
			(at 178.435 174.625 0)
			(effects
				(font
					(size 1.27 1.27)
					(thickness 0.15)
				)
				(justify left bottom)
				(hide yes)
			)
		)
		(pin "1"
		)
		(instances
			(project ""
				(path ""
					(reference "TP1")
					(unit 1)
				)
			)
		)
	)
	(symbol
		(lib_id "antmicroResistors0603:R_0R_22.4A_0603")
		(at 285.115 119.38 0)
		(mirror y)
		(unit 1)
		(exclude_from_sim no)
		(in_bom yes)
		(on_board yes)
		(dnp no)
		(property "Reference" "R46"
			(at 285.115 118.11 0)
			(effects
				(font
					(size 1.27 1.27)
					(thickness 0.15)
				)
				(justify right)
			)
		)
		(property "Value" "R_0R_22.4A_0603"
			(at 282.575 110.49 0)
			(effects
				(font
					(size 1.27 1.27)
					(thickness 0.15)
				)
				(hide yes)
			)
		)
		(property "Footprint" "antmicro-footprints:R_0603_1608Metric"
			(at 269.875 129.54 0)
			(effects
				(font
					(size 1.27 1.27)
					(thickness 0.15)
				)
				(justify left bottom)
				(hide yes)
			)
		)
		(property "Datasheet" "https://fscdn.rohm.com/en/products/databook/datasheet/passive/resistor/chip_resistor/pmr-jpw-e.pdf"
			(at 269.875 132.08 0)
			(effects
				(font
					(size 1.27 1.27)
					(thickness 0.15)
				)
				(justify left bottom)
				(hide yes)
			)
		)
		(property "Description" ""
			(at 285.115 119.38 0)
			(effects
				(font
					(size 1.27 1.27)
				)
			)
		)
		(property "MPN" "PMR03EZPJ000"
			(at 269.875 134.62 0)
			(effects
				(font
					(size 1.27 1.27)
					(thickness 0.15)
				)
				(justify left bottom)
				(hide yes)
			)
		)
		(property "Manufacturer" "ROHM Semiconductor"
			(at 269.875 137.16 0)
			(effects
				(font
					(size 1.27 1.27)
					(thickness 0.15)
				)
				(justify left bottom)
				(hide yes)
			)
		)
		(property "Val" "0R"
			(at 278.765 118.11 0)
			(effects
				(font
					(size 1.27 1.27)
					(thickness 0.15)
				)
			)
		)
		(property "Max. Curr." "22.4A"
			(at 282.575 121.92 0)
			(effects
				(font
					(size 1.27 1.27)
					(thickness 0.15)
				)
			)
		)
		(property "Author" "Antmicro"
			(at 269.875 142.24 0)
			(effects
				(font
					(size 1.27 1.27)
					(thickness 0.15)
				)
				(justify left bottom)
				(hide yes)
			)
		)
		(property "License" "Apache-2.0"
			(at 269.875 144.78 0)
			(effects
				(font
					(size 1.27 1.27)
					(thickness 0.15)
				)
				(justify left bottom)
				(hide yes)
			)
		)
		(property "Tolerance" "template_tolerance"
			(at 264.795 129.54 0)
			(effects
				(font
					(size 1.27 1.27)
				)
				(justify left bottom)
				(hide yes)
			)
		)
		(pin "1"
		)
		(pin "2"
		)
		(instances
			(project ""
				(path ""
					(reference "R46")
					(unit 1)
				)
			)
		)
	)
	(symbol
		(lib_id "antmicropower:+1V1")
		(at 158.75 177.165 0)
		(unit 1)
		(exclude_from_sim no)
		(in_bom yes)
		(on_board yes)
		(dnp no)
		(fields_autoplaced yes)
		(property "Reference" "#PWR0156"
			(at 158.75 180.975 0)
			(effects
				(font
					(size 1.27 1.27)
				)
				(hide yes)
			)
		)
		(property "Value" "+1V1"
			(at 158.75 172.085 0)
			(effects
				(font
					(size 1.27 1.27)
				)
			)
		)
		(property "Footprint" ""
			(at 158.75 177.165 0)
			(effects
				(font
					(size 1.27 1.27)
				)
				(hide yes)
			)
		)
		(property "Datasheet" ""
			(at 158.75 177.165 0)
			(effects
				(font
					(size 1.27 1.27)
				)
				(hide yes)
			)
		)
		(property "Description" ""
			(at 158.75 177.165 0)
			(effects
				(font
					(size 1.27 1.27)
				)
			)
		)
		(pin "1"
		)
		(instances
			(project ""
				(path ""
					(reference "#PWR0156")
					(unit 1)
				)
			)
		)
	)
	(symbol
		(lib_id "antmicropower:GND")
		(at 219.71 203.835 0)
		(unit 1)
		(exclude_from_sim no)
		(in_bom yes)
		(on_board yes)
		(dnp no)
		(fields_autoplaced yes)
		(property "Reference" "#PWR0211"
			(at 228.6 206.375 0)
			(effects
				(font
					(size 1.27 1.27)
					(thickness 0.15)
				)
				(justify left bottom)
				(hide yes)
			)
		)
		(property "Value" "GND"
			(at 219.71 208.28 0)
			(effects
				(font
					(size 1.27 1.27)
					(thickness 0.15)
				)
			)
		)
		(property "Footprint" ""
			(at 228.6 211.455 0)
			(effects
				(font
					(size 1.27 1.27)
					(thickness 0.15)
				)
				(justify left bottom)
				(hide yes)
			)
		)
		(property "Datasheet" ""
			(at 228.6 216.535 0)
			(effects
				(font
					(size 1.27 1.27)
					(thickness 0.15)
				)
				(justify left bottom)
				(hide yes)
			)
		)
		(property "Description" ""
			(at 219.71 203.835 0)
			(effects
				(font
					(size 1.27 1.27)
				)
			)
		)
		(property "Author" "Antmicro"
			(at 228.6 211.455 0)
			(effects
				(font
					(size 1.27 1.27)
					(thickness 0.15)
				)
				(justify left bottom)
				(hide yes)
			)
		)
		(property "License" "Apache-2.0"
			(at 228.6 213.995 0)
			(effects
				(font
					(size 1.27 1.27)
					(thickness 0.15)
				)
				(justify left bottom)
				(hide yes)
			)
		)
		(pin "1"
		)
		(instances
			(project ""
				(path ""
					(reference "#PWR0211")
					(unit 1)
				)
			)
		)
	)
	(symbol
		(lib_id "antmicroTestPoints:TP_0.75mm_SMD")
		(at 274.955 72.39 90)
		(unit 1)
		(exclude_from_sim no)
		(in_bom yes)
		(on_board yes)
		(dnp no)
		(property "Reference" "TP4"
			(at 272.415 68.58 0)
			(effects
				(font
					(size 1.27 1.27)
					(thickness 0.15)
				)
			)
		)
		(property "Value" "TP_0.75mm_SMD"
			(at 278.765 61.595 0)
			(effects
				(font
					(size 1.27 1.27)
					(thickness 0.15)
				)
				(justify left bottom)
				(hide yes)
			)
		)
		(property "Footprint" "antmicro-footprints:TP_SMD_0.75mm"
			(at 281.305 61.595 0)
			(effects
				(font
					(size 1.27 1.27)
					(thickness 0.15)
				)
				(justify left bottom)
				(hide yes)
			)
		)
		(property "Datasheet" ""
			(at 287.655 54.61 0)
			(effects
				(font
					(size 1.27 1.27)
					(thickness 0.15)
				)
				(justify left bottom)
				(hide yes)
			)
		)
		(property "Description" ""
			(at 274.955 72.39 0)
			(effects
				(font
					(size 1.27 1.27)
				)
			)
		)
		(property "MPN" ""
			(at 286.385 61.595 0)
			(effects
				(font
					(size 1.27 1.27)
					(thickness 0.15)
				)
				(justify left bottom)
				(hide yes)
			)
		)
		(property "Manufacturer" ""
			(at 281.305 61.595 0)
			(effects
				(font
					(size 1.27 1.27)
					(thickness 0.15)
				)
				(justify left bottom)
				(hide yes)
			)
		)
		(property "Author" "Antmicro"
			(at 283.845 61.595 0)
			(effects
				(font
					(size 1.27 1.27)
					(thickness 0.15)
				)
				(justify left bottom)
				(hide yes)
			)
		)
		(property "License" "Apache-2.0"
			(at 286.385 61.595 0)
			(effects
				(font
					(size 1.27 1.27)
					(thickness 0.15)
				)
				(justify left bottom)
				(hide yes)
			)
		)
		(pin "1"
		)
		(instances
			(project ""
				(path ""
					(reference "TP4")
					(unit 1)
				)
			)
		)
	)
	(symbol
		(lib_id "antmicroResistors0603:R_0R_22.4A_0603")
		(at 285.115 74.295 0)
		(mirror y)
		(unit 1)
		(exclude_from_sim no)
		(in_bom yes)
		(on_board yes)
		(dnp no)
		(property "Reference" "R43"
			(at 285.115 73.025 0)
			(effects
				(font
					(size 1.27 1.27)
					(thickness 0.15)
				)
				(justify right)
			)
		)
		(property "Value" "R_0R_22.4A_0603"
			(at 282.575 65.405 0)
			(effects
				(font
					(size 1.27 1.27)
					(thickness 0.15)
				)
				(hide yes)
			)
		)
		(property "Footprint" "antmicro-footprints:R_0603_1608Metric"
			(at 269.875 84.455 0)
			(effects
				(font
					(size 1.27 1.27)
					(thickness 0.15)
				)
				(justify left bottom)
				(hide yes)
			)
		)
		(property "Datasheet" "https://fscdn.rohm.com/en/products/databook/datasheet/passive/resistor/chip_resistor/pmr-jpw-e.pdf"
			(at 269.875 86.995 0)
			(effects
				(font
					(size 1.27 1.27)
					(thickness 0.15)
				)
				(justify left bottom)
				(hide yes)
			)
		)
		(property "Description" ""
			(at 285.115 74.295 0)
			(effects
				(font
					(size 1.27 1.27)
				)
			)
		)
		(property "MPN" "PMR03EZPJ000"
			(at 269.875 89.535 0)
			(effects
				(font
					(size 1.27 1.27)
					(thickness 0.15)
				)
				(justify left bottom)
				(hide yes)
			)
		)
		(property "Manufacturer" "ROHM Semiconductor"
			(at 269.875 92.075 0)
			(effects
				(font
					(size 1.27 1.27)
					(thickness 0.15)
				)
				(justify left bottom)
				(hide yes)
			)
		)
		(property "Val" "0R"
			(at 278.765 73.025 0)
			(effects
				(font
					(size 1.27 1.27)
					(thickness 0.15)
				)
			)
		)
		(property "Max. Curr." "22.4A"
			(at 282.575 76.835 0)
			(effects
				(font
					(size 1.27 1.27)
					(thickness 0.15)
				)
			)
		)
		(property "Author" "Antmicro"
			(at 269.875 97.155 0)
			(effects
				(font
					(size 1.27 1.27)
					(thickness 0.15)
				)
				(justify left bottom)
				(hide yes)
			)
		)
		(property "License" "Apache-2.0"
			(at 269.875 99.695 0)
			(effects
				(font
					(size 1.27 1.27)
					(thickness 0.15)
				)
				(justify left bottom)
				(hide yes)
			)
		)
		(property "Tolerance" "template_tolerance"
			(at 264.795 84.455 0)
			(effects
				(font
					(size 1.27 1.27)
				)
				(justify left bottom)
				(hide yes)
			)
		)
		(pin "1"
		)
		(pin "2"
		)
		(instances
			(project ""
				(path ""
					(reference "R43")
					(unit 1)
				)
			)
		)
	)
	(symbol
		(lib_id "antmicropower:GND")
		(at 266.7 95.25 0)
		(unit 1)
		(exclude_from_sim no)
		(in_bom yes)
		(on_board yes)
		(dnp no)
		(fields_autoplaced yes)
		(property "Reference" "#PWR0150"
			(at 275.59 97.79 0)
			(effects
				(font
					(size 1.27 1.27)
					(thickness 0.15)
				)
				(justify left bottom)
				(hide yes)
			)
		)
		(property "Value" "GND"
			(at 266.7 99.695 0)
			(effects
				(font
					(size 1.27 1.27)
					(thickness 0.15)
				)
			)
		)
		(property "Footprint" ""
			(at 275.59 102.87 0)
			(effects
				(font
					(size 1.27 1.27)
					(thickness 0.15)
				)
				(justify left bottom)
				(hide yes)
			)
		)
		(property "Datasheet" ""
			(at 275.59 107.95 0)
			(effects
				(font
					(size 1.27 1.27)
					(thickness 0.15)
				)
				(justify left bottom)
				(hide yes)
			)
		)
		(property "Description" ""
			(at 266.7 95.25 0)
			(effects
				(font
					(size 1.27 1.27)
				)
			)
		)
		(property "Author" "Antmicro"
			(at 275.59 102.87 0)
			(effects
				(font
					(size 1.27 1.27)
					(thickness 0.15)
				)
				(justify left bottom)
				(hide yes)
			)
		)
		(property "License" "Apache-2.0"
			(at 275.59 105.41 0)
			(effects
				(font
					(size 1.27 1.27)
					(thickness 0.15)
				)
				(justify left bottom)
				(hide yes)
			)
		)
		(pin "1"
		)
		(instances
			(project ""
				(path ""
					(reference "#PWR0150")
					(unit 1)
				)
			)
		)
	)
	(symbol
		(lib_id "antmicroResistors0402:R_120k_0402")
		(at 236.22 116.84 0)
		(unit 1)
		(exclude_from_sim no)
		(in_bom yes)
		(on_board yes)
		(dnp no)
		(property "Reference" "R40"
			(at 234.95 115.57 0)
			(effects
				(font
					(size 1.27 1.27)
					(thickness 0.15)
				)
			)
		)
		(property "Value" "R_120k_0402"
			(at 256.54 129.54 0)
			(effects
				(font
					(size 1.27 1.27)
					(thickness 0.15)
				)
				(justify left bottom)
				(hide yes)
			)
		)
		(property "Footprint" "antmicro-footprints:R_0402_1005Metric"
			(at 256.54 132.08 0)
			(effects
				(font
					(size 1.27 1.27)
					(thickness 0.15)
				)
				(justify left bottom)
				(hide yes)
			)
		)
		(property "Datasheet" "https://www.bourns.com/docs/product-datasheets/cr.pdf"
			(at 256.54 134.62 0)
			(effects
				(font
					(size 1.27 1.27)
					(thickness 0.15)
				)
				(justify left bottom)
				(hide yes)
			)
		)
		(property "Description" ""
			(at 236.22 116.84 0)
			(effects
				(font
					(size 1.27 1.27)
				)
			)
		)
		(property "MPN" "CR0402-FX-1203GLF"
			(at 256.54 137.16 0)
			(effects
				(font
					(size 1.27 1.27)
					(thickness 0.15)
				)
				(justify left bottom)
				(hide yes)
			)
		)
		(property "Manufacturer" "Bourns"
			(at 256.54 139.7 0)
			(effects
				(font
					(size 1.27 1.27)
					(thickness 0.15)
				)
				(justify left bottom)
				(hide yes)
			)
		)
		(property "License" "Apache-2.0"
			(at 256.54 142.24 0)
			(effects
				(font
					(size 1.27 1.27)
					(thickness 0.15)
				)
				(justify left bottom)
				(hide yes)
			)
		)
		(property "Author" "Antmicro"
			(at 256.54 144.78 0)
			(effects
				(font
					(size 1.27 1.27)
					(thickness 0.15)
				)
				(justify left bottom)
				(hide yes)
			)
		)
		(property "Val" "120k"
			(at 243.205 115.57 0)
			(effects
				(font
					(size 1.27 1.27)
					(thickness 0.15)
				)
			)
		)
		(property "Tolerance" "1%"
			(at 256.54 127 0)
			(effects
				(font
					(size 1.27 1.27)
				)
				(justify left bottom)
				(hide yes)
			)
		)
		(pin "1"
		)
		(pin "2"
		)
		(instances
			(project ""
				(path ""
					(reference "R40")
					(unit 1)
				)
			)
		)
	)
	(symbol
		(lib_id "antmicroTestPoints:TP_0.75mm_SMD")
		(at 274.955 102.235 90)
		(unit 1)
		(exclude_from_sim no)
		(in_bom yes)
		(on_board yes)
		(dnp no)
		(property "Reference" "TP6"
			(at 272.415 98.425 0)
			(effects
				(font
					(size 1.27 1.27)
					(thickness 0.15)
				)
			)
		)
		(property "Value" "TP_0.75mm_SMD"
			(at 278.765 91.44 0)
			(effects
				(font
					(size 1.27 1.27)
					(thickness 0.15)
				)
				(justify left bottom)
				(hide yes)
			)
		)
		(property "Footprint" "antmicro-footprints:TP_SMD_0.75mm"
			(at 281.305 91.44 0)
			(effects
				(font
					(size 1.27 1.27)
					(thickness 0.15)
				)
				(justify left bottom)
				(hide yes)
			)
		)
		(property "Datasheet" ""
			(at 287.655 84.455 0)
			(effects
				(font
					(size 1.27 1.27)
					(thickness 0.15)
				)
				(justify left bottom)
				(hide yes)
			)
		)
		(property "Description" ""
			(at 274.955 102.235 0)
			(effects
				(font
					(size 1.27 1.27)
				)
			)
		)
		(property "MPN" ""
			(at 286.385 91.44 0)
			(effects
				(font
					(size 1.27 1.27)
					(thickness 0.15)
				)
				(justify left bottom)
				(hide yes)
			)
		)
		(property "Manufacturer" ""
			(at 281.305 91.44 0)
			(effects
				(font
					(size 1.27 1.27)
					(thickness 0.15)
				)
				(justify left bottom)
				(hide yes)
			)
		)
		(property "Author" "Antmicro"
			(at 283.845 91.44 0)
			(effects
				(font
					(size 1.27 1.27)
					(thickness 0.15)
				)
				(justify left bottom)
				(hide yes)
			)
		)
		(property "License" "Apache-2.0"
			(at 286.385 91.44 0)
			(effects
				(font
					(size 1.27 1.27)
					(thickness 0.15)
				)
				(justify left bottom)
				(hide yes)
			)
		)
		(pin "1"
		)
		(instances
			(project ""
				(path ""
					(reference "TP6")
					(unit 1)
				)
			)
		)
	)
	(symbol
		(lib_id "antmicroTestPoints:TP_0.75mm_SMD")
		(at 274.955 117.475 90)
		(unit 1)
		(exclude_from_sim no)
		(in_bom yes)
		(on_board yes)
		(dnp no)
		(property "Reference" "TP7"
			(at 272.415 113.665 0)
			(effects
				(font
					(size 1.27 1.27)
					(thickness 0.15)
				)
			)
		)
		(property "Value" "TP_0.75mm_SMD"
			(at 278.765 106.68 0)
			(effects
				(font
					(size 1.27 1.27)
					(thickness 0.15)
				)
				(justify left bottom)
				(hide yes)
			)
		)
		(property "Footprint" "antmicro-footprints:TP_SMD_0.75mm"
			(at 281.305 106.68 0)
			(effects
				(font
					(size 1.27 1.27)
					(thickness 0.15)
				)
				(justify left bottom)
				(hide yes)
			)
		)
		(property "Datasheet" ""
			(at 287.655 99.695 0)
			(effects
				(font
					(size 1.27 1.27)
					(thickness 0.15)
				)
				(justify left bottom)
				(hide yes)
			)
		)
		(property "Description" ""
			(at 274.955 117.475 0)
			(effects
				(font
					(size 1.27 1.27)
				)
			)
		)
		(property "MPN" ""
			(at 286.385 106.68 0)
			(effects
				(font
					(size 1.27 1.27)
					(thickness 0.15)
				)
				(justify left bottom)
				(hide yes)
			)
		)
		(property "Manufacturer" ""
			(at 281.305 106.68 0)
			(effects
				(font
					(size 1.27 1.27)
					(thickness 0.15)
				)
				(justify left bottom)
				(hide yes)
			)
		)
		(property "Author" "Antmicro"
			(at 283.845 106.68 0)
			(effects
				(font
					(size 1.27 1.27)
					(thickness 0.15)
				)
				(justify left bottom)
				(hide yes)
			)
		)
		(property "License" "Apache-2.0"
			(at 286.385 106.68 0)
			(effects
				(font
					(size 1.27 1.27)
					(thickness 0.15)
				)
				(justify left bottom)
				(hide yes)
			)
		)
		(pin "1"
		)
		(instances
			(project ""
				(path ""
					(reference "TP7")
					(unit 1)
				)
			)
		)
	)
	(symbol
		(lib_id "antmicroResistors0402:R_1k_0402")
		(at 243.84 193.04 270)
		(unit 1)
		(exclude_from_sim no)
		(in_bom yes)
		(on_board yes)
		(dnp no)
		(property "Reference" "R42"
			(at 245.11 194.31 90)
			(effects
				(font
					(size 1.27 1.27)
					(thickness 0.15)
				)
				(justify left)
			)
		)
		(property "Value" "R_1k_0402"
			(at 231.14 213.36 0)
			(effects
				(font
					(size 1.27 1.27)
					(thickness 0.15)
				)
				(justify left bottom)
				(hide yes)
			)
		)
		(property "Footprint" "antmicro-footprints:R_0402_1005Metric"
			(at 228.6 213.36 0)
			(effects
				(font
					(size 1.27 1.27)
					(thickness 0.15)
				)
				(justify left bottom)
				(hide yes)
			)
		)
		(property "Datasheet" "https://www.bourns.com/docs/product-datasheets/cr.pdf"
			(at 226.06 213.36 0)
			(effects
				(font
					(size 1.27 1.27)
					(thickness 0.15)
				)
				(justify left bottom)
				(hide yes)
			)
		)
		(property "Description" ""
			(at 243.84 193.04 0)
			(effects
				(font
					(size 1.27 1.27)
				)
			)
		)
		(property "MPN" "CR0402-FX-1001GLF"
			(at 223.52 213.36 0)
			(effects
				(font
					(size 1.27 1.27)
					(thickness 0.15)
				)
				(justify left bottom)
				(hide yes)
			)
		)
		(property "Manufacturer" "Bourns"
			(at 220.98 213.36 0)
			(effects
				(font
					(size 1.27 1.27)
					(thickness 0.15)
				)
				(justify left bottom)
				(hide yes)
			)
		)
		(property "License" "Apache-2.0"
			(at 218.44 213.36 0)
			(effects
				(font
					(size 1.27 1.27)
					(thickness 0.15)
				)
				(justify left bottom)
				(hide yes)
			)
		)
		(property "Author" "Antmicro"
			(at 215.9 213.36 0)
			(effects
				(font
					(size 1.27 1.27)
					(thickness 0.15)
				)
				(justify left bottom)
				(hide yes)
			)
		)
		(property "Val" "1k"
			(at 245.11 196.85 90)
			(effects
				(font
					(size 1.27 1.27)
					(thickness 0.15)
				)
				(justify left)
			)
		)
		(property "Tolerance" "1%"
			(at 233.68 213.36 0)
			(effects
				(font
					(size 1.27 1.27)
				)
				(justify left bottom)
				(hide yes)
			)
		)
		(pin "1"
		)
		(pin "2"
		)
		(instances
			(project ""
				(path ""
					(reference "R42")
					(unit 1)
				)
			)
		)
	)
	(symbol
		(lib_id "antmicropower:GND")
		(at 302.26 187.325 0)
		(unit 1)
		(exclude_from_sim no)
		(in_bom yes)
		(on_board yes)
		(dnp no)
		(fields_autoplaced yes)
		(property "Reference" "#PWR0205"
			(at 311.15 189.865 0)
			(effects
				(font
					(size 1.27 1.27)
					(thickness 0.15)
				)
				(justify left bottom)
				(hide yes)
			)
		)
		(property "Value" "GND"
			(at 302.26 191.77 0)
			(effects
				(font
					(size 1.27 1.27)
					(thickness 0.15)
				)
			)
		)
		(property "Footprint" ""
			(at 311.15 194.945 0)
			(effects
				(font
					(size 1.27 1.27)
					(thickness 0.15)
				)
				(justify left bottom)
				(hide yes)
			)
		)
		(property "Datasheet" ""
			(at 311.15 200.025 0)
			(effects
				(font
					(size 1.27 1.27)
					(thickness 0.15)
				)
				(justify left bottom)
				(hide yes)
			)
		)
		(property "Description" ""
			(at 302.26 187.325 0)
			(effects
				(font
					(size 1.27 1.27)
				)
			)
		)
		(property "Author" "Antmicro"
			(at 311.15 194.945 0)
			(effects
				(font
					(size 1.27 1.27)
					(thickness 0.15)
				)
				(justify left bottom)
				(hide yes)
			)
		)
		(property "License" "Apache-2.0"
			(at 311.15 197.485 0)
			(effects
				(font
					(size 1.27 1.27)
					(thickness 0.15)
				)
				(justify left bottom)
				(hide yes)
			)
		)
		(pin "1"
		)
		(instances
			(project ""
				(path ""
					(reference "#PWR0205")
					(unit 1)
				)
			)
		)
	)
)
